(kicad_sch (version 20230121) (generator eeschema)

  (paper "A3")

  (title_block
    (title "HDMI-MIPI Bridge")
    (date "2023-07-20")
    (rev "1.3.1")
  )

  (junction (at 223.52 260.35) (diameter 0) (color 0 0 0 0)
  )
  (junction (at 234.95 242.57) (diameter 0) (color 0 0 0 0)
  )
  (junction (at 363.22 85.09) (diameter 0) (color 0 0 0 0)
  )
  (junction (at 116.84 46.99) (diameter 0) (color 0 0 0 0)
  )
  (junction (at 215.265 196.85) (diameter 0) (color 0 0 0 0)
  )
  (junction (at 186.69 207.01) (diameter 0) (color 0 0 0 0)
  )
  (junction (at 116.84 62.23) (diameter 0) (color 0 0 0 0)
  )
  (junction (at 90.17 74.93) (diameter 0) (color 0 0 0 0)
  )
  (junction (at 332.74 173.99) (diameter 0) (color 0 0 0 0)
  )
  (junction (at 234.95 260.35) (diameter 0) (color 0 0 0 0)
  )
  (junction (at 223.52 227.33) (diameter 0) (color 0 0 0 0)
  )
  (junction (at 223.52 166.37) (diameter 0) (color 0 0 0 0)
  )
  (junction (at 90.17 72.39) (diameter 0) (color 0 0 0 0)
  )
  (junction (at 90.17 80.01) (diameter 0) (color 0 0 0 0)
  )
  (junction (at 339.09 39.37) (diameter 0) (color 0 0 0 0)
  )
  (junction (at 360.68 207.01) (diameter 0) (color 0 0 0 0)
  )
  (junction (at 294.64 39.37) (diameter 0) (color 0 0 0 0)
  )
  (junction (at 156.21 214.63) (diameter 0) (color 0 0 0 0)
  )
  (junction (at 384.81 39.37) (diameter 0) (color 0 0 0 0)
  )
  (junction (at 332.74 176.53) (diameter 0) (color 0 0 0 0)
  )
  (junction (at 318.77 39.37) (diameter 0) (color 0 0 0 0)
  )
  (junction (at 199.39 237.49) (diameter 0) (color 0 0 0 0)
  )
  (junction (at 124.46 99.06) (diameter 0) (color 0 0 0 0)
  )
  (junction (at 90.17 77.47) (diameter 0) (color 0 0 0 0)
  )
  (junction (at 372.11 104.14) (diameter 0) (color 0 0 0 0)
  )
  (junction (at 215.265 212.09) (diameter 0) (color 0 0 0 0)
  )
  (junction (at 328.93 39.37) (diameter 0) (color 0 0 0 0)
  )
  (junction (at 333.375 39.37) (diameter 0) (color 0 0 0 0)
  )
  (junction (at 332.74 209.55) (diameter 0) (color 0 0 0 0)
  )
  (junction (at 367.03 39.37) (diameter 0) (color 0 0 0 0)
  )
  (junction (at 305.435 85.09) (diameter 0) (color 0 0 0 0)
  )
  (junction (at 240.03 166.37) (diameter 0) (color 0 0 0 0)
  )
  (junction (at 129.54 99.06) (diameter 0) (color 0 0 0 0)
  )
  (junction (at 240.03 181.61) (diameter 0) (color 0 0 0 0)
  )
  (junction (at 116.84 54.61) (diameter 0) (color 0 0 0 0)
  )
  (junction (at 223.52 181.61) (diameter 0) (color 0 0 0 0)
  )
  (junction (at 215.265 166.37) (diameter 0) (color 0 0 0 0)
  )
  (junction (at 215.265 242.57) (diameter 0) (color 0 0 0 0)
  )
  (junction (at 223.52 242.57) (diameter 0) (color 0 0 0 0)
  )
  (junction (at 223.52 196.85) (diameter 0) (color 0 0 0 0)
  )
  (junction (at 330.2 101.6) (diameter 0) (color 0 0 0 0)
  )
  (junction (at 223.52 212.09) (diameter 0) (color 0 0 0 0)
  )
  (junction (at 215.265 227.33) (diameter 0) (color 0 0 0 0)
  )
  (junction (at 186.69 240.03) (diameter 0) (color 0 0 0 0)
  )
  (junction (at 360.68 173.99) (diameter 0) (color 0 0 0 0)
  )
  (junction (at 321.31 104.14) (diameter 0) (color 0 0 0 0)
  )
  (junction (at 215.265 260.35) (diameter 0) (color 0 0 0 0)
  )
  (junction (at 234.95 212.09) (diameter 0) (color 0 0 0 0)
  )
  (junction (at 149.86 201.93) (diameter 0) (color 0 0 0 0)
  )
  (junction (at 215.265 181.61) (diameter 0) (color 0 0 0 0)
  )
  (junction (at 330.2 85.09) (diameter 0) (color 0 0 0 0)
  )
  (junction (at 234.95 227.33) (diameter 0) (color 0 0 0 0)
  )
  (junction (at 257.81 227.33) (diameter 0) (color 0 0 0 0)
  )
  (junction (at 192.405 240.03) (diameter 0) (color 0 0 0 0)
  )
  (junction (at 257.81 242.57) (diameter 0) (color 0 0 0 0)
  )
  (junction (at 383.54 85.09) (diameter 0) (color 0 0 0 0)
  )
  (junction (at 363.22 101.6) (diameter 0) (color 0 0 0 0)
  )
  (junction (at 304.8 39.37) (diameter 0) (color 0 0 0 0)
  )
  (junction (at 156.21 219.71) (diameter 0) (color 0 0 0 0)
  )
  (junction (at 372.11 85.09) (diameter 0) (color 0 0 0 0)
  )
  (junction (at 116.84 77.47) (diameter 0) (color 0 0 0 0)
  )
  (junction (at 332.74 207.01) (diameter 0) (color 0 0 0 0)
  )
  (junction (at 321.31 85.09) (diameter 0) (color 0 0 0 0)
  )

  (no_connect (at 158.75 207.01))
  (no_connect (at 73.66 189.23))
  (no_connect (at 105.41 231.14))
  (no_connect (at 105.41 243.84))
  (no_connect (at 105.41 233.68))
  (no_connect (at 105.41 228.6))
  (no_connect (at 105.41 236.22))

  (wire (pts (xy 305.435 85.09) (xy 321.31 85.09))
    (stroke (width 0) (type default))
  )
  (wire (pts (xy 234.95 242.57) (xy 234.95 245.11))
    (stroke (width 0) (type default))
  )
  (wire (pts (xy 328.93 39.37) (xy 318.77 39.37))
    (stroke (width 0) (type default))
  )
  (wire (pts (xy 201.93 196.85) (xy 201.93 166.37))
    (stroke (width 0) (type default))
  )
  (wire (pts (xy 234.95 212.09) (xy 248.285 212.09))
    (stroke (width 0) (type default))
  )
  (wire (pts (xy 151.13 60.325) (xy 167.64 60.325))
    (stroke (width 0) (type default))
  )
  (wire (pts (xy 129.54 98.425) (xy 129.54 99.06))
    (stroke (width 0) (type default))
  )
  (wire (pts (xy 304.8 46.99) (xy 304.8 49.53))
    (stroke (width 0) (type default))
  )
  (wire (pts (xy 294.64 39.37) (xy 294.64 41.91))
    (stroke (width 0) (type default))
  )
  (wire (pts (xy 330.2 101.6) (xy 337.82 101.6))
    (stroke (width 0) (type default))
  )
  (wire (pts (xy 359.41 39.37) (xy 367.03 39.37))
    (stroke (width 0) (type default))
  )
  (wire (pts (xy 361.95 207.01) (xy 360.68 207.01))
    (stroke (width 0) (type default))
  )
  (wire (pts (xy 240.03 166.37) (xy 240.03 181.61))
    (stroke (width 0) (type default))
  )
  (wire (pts (xy 156.21 173.99) (xy 156.21 187.96))
    (stroke (width 0) (type default))
  )
  (wire (pts (xy 340.36 39.37) (xy 339.09 39.37))
    (stroke (width 0) (type default))
  )
  (wire (pts (xy 234.95 242.57) (xy 248.285 242.57))
    (stroke (width 0) (type default))
  )
  (wire (pts (xy 339.09 46.355) (xy 339.09 44.45))
    (stroke (width 0) (type default))
  )
  (wire (pts (xy 215.265 259.715) (xy 215.265 260.35))
    (stroke (width 0) (type default))
  )
  (wire (pts (xy 223.52 250.19) (xy 223.52 252.73))
    (stroke (width 0) (type default))
  )
  (wire (pts (xy 215.265 260.35) (xy 223.52 260.35))
    (stroke (width 0) (type default))
  )
  (wire (pts (xy 100.33 74.93) (xy 119.38 74.93))
    (stroke (width 0) (type default))
  )
  (wire (pts (xy 186.055 70.485) (xy 186.055 73.025))
    (stroke (width 0) (type default))
  )
  (wire (pts (xy 304.8 39.37) (xy 309.245 39.37))
    (stroke (width 0) (type default))
  )
  (wire (pts (xy 116.84 54.61) (xy 116.84 62.23))
    (stroke (width 0) (type default))
  )
  (wire (pts (xy 215.265 196.85) (xy 223.52 196.85))
    (stroke (width 0) (type default))
  )
  (wire (pts (xy 29.21 31.75) (xy 50.8 31.75))
    (stroke (width 0) (type default))
  )
  (wire (pts (xy 100.33 67.31) (xy 119.38 67.31))
    (stroke (width 0) (type default))
  )
  (wire (pts (xy 104.14 184.15) (xy 118.11 184.15))
    (stroke (width 0) (type default))
  )
  (wire (pts (xy 29.21 82.55) (xy 50.8 82.55))
    (stroke (width 0) (type default))
  )
  (wire (pts (xy 223.52 219.71) (xy 223.52 222.25))
    (stroke (width 0) (type default))
  )
  (wire (pts (xy 104.14 189.23) (xy 118.11 189.23))
    (stroke (width 0) (type default))
  )
  (wire (pts (xy 76.2 72.39) (xy 90.17 72.39))
    (stroke (width 0) (type default))
  )
  (wire (pts (xy 234.95 260.35) (xy 248.285 260.35))
    (stroke (width 0) (type default))
  )
  (wire (pts (xy 29.21 54.61) (xy 50.8 54.61))
    (stroke (width 0) (type default))
  )
  (wire (pts (xy 116.84 46.99) (xy 116.84 54.61))
    (stroke (width 0) (type default))
  )
  (wire (pts (xy 59.69 166.37) (xy 73.66 166.37))
    (stroke (width 0) (type default))
  )
  (wire (pts (xy 335.28 106.68) (xy 337.82 106.68))
    (stroke (width 0) (type default))
  )
  (wire (pts (xy 151.13 57.785) (xy 167.64 57.785))
    (stroke (width 0) (type default))
  )
  (wire (pts (xy 29.21 64.77) (xy 50.8 64.77))
    (stroke (width 0) (type default))
  )
  (wire (pts (xy 253.365 212.09) (xy 259.08 212.09))
    (stroke (width 0) (type default))
  )
  (wire (pts (xy 184.15 237.49) (xy 199.39 237.49))
    (stroke (width 0) (type default))
  )
  (wire (pts (xy 186.69 250.19) (xy 186.69 252.73))
    (stroke (width 0) (type default))
  )
  (wire (pts (xy 184.15 240.03) (xy 186.69 240.03))
    (stroke (width 0) (type default))
  )
  (wire (pts (xy 29.21 62.23) (xy 50.8 62.23))
    (stroke (width 0) (type default))
  )
  (wire (pts (xy 383.54 92.71) (xy 383.54 95.25))
    (stroke (width 0) (type default))
  )
  (wire (pts (xy 151.13 70.485) (xy 167.64 70.485))
    (stroke (width 0) (type default))
  )
  (wire (pts (xy 209.55 227.33) (xy 215.265 227.33))
    (stroke (width 0) (type default))
  )
  (wire (pts (xy 92.71 241.3) (xy 105.41 241.3))
    (stroke (width 0) (type default))
  )
  (wire (pts (xy 240.03 181.61) (xy 240.03 196.85))
    (stroke (width 0) (type default))
  )
  (wire (pts (xy 295.91 101.6) (xy 330.2 101.6))
    (stroke (width 0) (type default))
  )
  (wire (pts (xy 223.52 242.57) (xy 215.265 242.57))
    (stroke (width 0) (type default))
  )
  (wire (pts (xy 328.93 46.99) (xy 328.93 49.53))
    (stroke (width 0) (type default))
  )
  (wire (pts (xy 333.375 39.37) (xy 328.93 39.37))
    (stroke (width 0) (type default))
  )
  (wire (pts (xy 102.87 246.38) (xy 102.87 252.73))
    (stroke (width 0) (type default))
  )
  (wire (pts (xy 223.52 234.95) (xy 223.52 237.49))
    (stroke (width 0) (type default))
  )
  (wire (pts (xy 116.84 62.23) (xy 116.84 77.47))
    (stroke (width 0) (type default))
  )
  (wire (pts (xy 223.52 173.99) (xy 223.52 176.53))
    (stroke (width 0) (type default))
  )
  (wire (pts (xy 199.39 240.03) (xy 199.39 237.49))
    (stroke (width 0) (type default))
  )
  (wire (pts (xy 334.01 209.55) (xy 332.74 209.55))
    (stroke (width 0) (type default))
  )
  (wire (pts (xy 223.52 260.35) (xy 223.52 262.89))
    (stroke (width 0) (type default))
  )
  (wire (pts (xy 156.21 214.63) (xy 158.75 214.63))
    (stroke (width 0) (type default))
  )
  (wire (pts (xy 29.21 39.37) (xy 50.8 39.37))
    (stroke (width 0) (type default))
  )
  (wire (pts (xy 215.265 226.695) (xy 215.265 227.33))
    (stroke (width 0) (type default))
  )
  (wire (pts (xy 304.8 39.37) (xy 304.8 41.91))
    (stroke (width 0) (type default))
  )
  (wire (pts (xy 29.21 49.53) (xy 50.8 49.53))
    (stroke (width 0) (type default))
  )
  (wire (pts (xy 124.46 99.06) (xy 129.54 99.06))
    (stroke (width 0) (type default))
  )
  (wire (pts (xy 90.17 77.47) (xy 90.17 80.01))
    (stroke (width 0) (type default))
  )
  (wire (pts (xy 332.74 176.53) (xy 332.74 179.07))
    (stroke (width 0) (type default))
  )
  (wire (pts (xy 78.74 82.55) (xy 76.2 82.55))
    (stroke (width 0) (type default))
  )
  (wire (pts (xy 105.41 238.76) (xy 83.82 238.76))
    (stroke (width 0) (type default))
  )
  (wire (pts (xy 253.365 242.57) (xy 257.81 242.57))
    (stroke (width 0) (type default))
  )
  (wire (pts (xy 201.93 237.49) (xy 201.93 260.35))
    (stroke (width 0) (type default))
  )
  (wire (pts (xy 156.21 196.85) (xy 158.75 196.85))
    (stroke (width 0) (type default))
  )
  (wire (pts (xy 100.33 69.85) (xy 119.38 69.85))
    (stroke (width 0) (type default))
  )
  (wire (pts (xy 358.14 85.09) (xy 358.14 99.06))
    (stroke (width 0) (type default))
  )
  (wire (pts (xy 384.81 46.99) (xy 384.81 49.53))
    (stroke (width 0) (type default))
  )
  (wire (pts (xy 335.28 85.09) (xy 335.28 99.06))
    (stroke (width 0) (type default))
  )
  (wire (pts (xy 184.15 196.85) (xy 201.93 196.85))
    (stroke (width 0) (type default))
  )
  (wire (pts (xy 330.2 93.98) (xy 330.2 101.6))
    (stroke (width 0) (type default))
  )
  (wire (pts (xy 100.33 49.53) (xy 119.38 49.53))
    (stroke (width 0) (type default))
  )
  (wire (pts (xy 333.375 38.735) (xy 333.375 39.37))
    (stroke (width 0) (type default))
  )
  (wire (pts (xy 59.69 171.45) (xy 73.66 171.45))
    (stroke (width 0) (type default))
  )
  (wire (pts (xy 339.09 44.45) (xy 340.36 44.45))
    (stroke (width 0) (type default))
  )
  (wire (pts (xy 360.68 173.99) (xy 361.95 173.99))
    (stroke (width 0) (type default))
  )
  (wire (pts (xy 52.07 201.93) (xy 73.66 201.93))
    (stroke (width 0) (type default))
  )
  (wire (pts (xy 100.33 82.55) (xy 119.38 82.55))
    (stroke (width 0) (type default))
  )
  (wire (pts (xy 184.15 70.485) (xy 186.055 70.485))
    (stroke (width 0) (type default))
  )
  (wire (pts (xy 151.13 52.705) (xy 167.64 52.705))
    (stroke (width 0) (type default))
  )
  (wire (pts (xy 223.52 166.37) (xy 223.52 168.91))
    (stroke (width 0) (type default))
  )
  (wire (pts (xy 223.52 267.97) (xy 223.52 270.51))
    (stroke (width 0) (type default))
  )
  (wire (pts (xy 209.55 217.17) (xy 186.69 217.17))
    (stroke (width 0) (type default))
  )
  (wire (pts (xy 330.2 85.09) (xy 335.28 85.09))
    (stroke (width 0) (type default))
  )
  (wire (pts (xy 104.14 173.99) (xy 118.11 173.99))
    (stroke (width 0) (type default))
  )
  (wire (pts (xy 360.68 173.99) (xy 360.68 177.8))
    (stroke (width 0) (type default))
  )
  (wire (pts (xy 116.84 46.99) (xy 119.38 46.99))
    (stroke (width 0) (type default))
  )
  (wire (pts (xy 100.33 64.77) (xy 119.38 64.77))
    (stroke (width 0) (type default))
  )
  (wire (pts (xy 384.81 39.37) (xy 384.81 41.91))
    (stroke (width 0) (type default))
  )
  (wire (pts (xy 355.6 177.8) (xy 355.6 176.53))
    (stroke (width 0) (type default))
  )
  (wire (pts (xy 355.6 210.82) (xy 355.6 209.55))
    (stroke (width 0) (type default))
  )
  (wire (pts (xy 156.21 212.09) (xy 156.21 214.63))
    (stroke (width 0) (type default))
  )
  (wire (pts (xy 116.84 54.61) (xy 119.38 54.61))
    (stroke (width 0) (type default))
  )
  (wire (pts (xy 29.21 34.29) (xy 50.8 34.29))
    (stroke (width 0) (type default))
  )
  (wire (pts (xy 205.74 242.57) (xy 215.265 242.57))
    (stroke (width 0) (type default))
  )
  (wire (pts (xy 83.82 238.76) (xy 83.82 252.73))
    (stroke (width 0) (type default))
  )
  (wire (pts (xy 186.69 204.47) (xy 186.69 207.01))
    (stroke (width 0) (type default))
  )
  (wire (pts (xy 223.52 196.85) (xy 232.41 196.85))
    (stroke (width 0) (type default))
  )
  (wire (pts (xy 363.22 101.6) (xy 391.16 101.6))
    (stroke (width 0) (type default))
  )
  (wire (pts (xy 360.68 207.01) (xy 354.33 207.01))
    (stroke (width 0) (type default))
  )
  (wire (pts (xy 59.69 158.75) (xy 73.66 158.75))
    (stroke (width 0) (type default))
  )
  (wire (pts (xy 124.46 99.06) (xy 124.46 105.41))
    (stroke (width 0) (type default))
  )
  (wire (pts (xy 205.74 227.33) (xy 205.74 242.57))
    (stroke (width 0) (type default))
  )
  (wire (pts (xy 90.17 72.39) (xy 90.17 74.93))
    (stroke (width 0) (type default))
  )
  (wire (pts (xy 372.11 85.09) (xy 372.11 88.9))
    (stroke (width 0) (type default))
  )
  (wire (pts (xy 151.13 65.405) (xy 167.64 65.405))
    (stroke (width 0) (type default))
  )
  (wire (pts (xy 149.86 184.15) (xy 149.86 187.96))
    (stroke (width 0) (type default))
  )
  (wire (pts (xy 305.435 82.55) (xy 305.435 85.09))
    (stroke (width 0) (type default))
  )
  (wire (pts (xy 363.22 93.98) (xy 363.22 101.6))
    (stroke (width 0) (type default))
  )
  (wire (pts (xy 151.13 62.865) (xy 167.64 62.865))
    (stroke (width 0) (type default))
  )
  (wire (pts (xy 151.13 67.945) (xy 167.64 67.945))
    (stroke (width 0) (type default))
  )
  (wire (pts (xy 104.14 168.91) (xy 118.11 168.91))
    (stroke (width 0) (type default))
  )
  (wire (pts (xy 355.6 104.14) (xy 372.11 104.14))
    (stroke (width 0) (type default))
  )
  (wire (pts (xy 59.69 184.15) (xy 73.66 184.15))
    (stroke (width 0) (type default))
  )
  (wire (pts (xy 76.2 80.01) (xy 90.17 80.01))
    (stroke (width 0) (type default))
  )
  (wire (pts (xy 223.52 212.09) (xy 234.95 212.09))
    (stroke (width 0) (type default))
  )
  (wire (pts (xy 234.95 219.71) (xy 234.95 222.25))
    (stroke (width 0) (type default))
  )
  (wire (pts (xy 149.86 193.04) (xy 149.86 201.93))
    (stroke (width 0) (type default))
  )
  (wire (pts (xy 223.52 260.35) (xy 234.95 260.35))
    (stroke (width 0) (type default))
  )
  (wire (pts (xy 156.21 193.04) (xy 156.21 196.85))
    (stroke (width 0) (type default))
  )
  (wire (pts (xy 78.74 90.805) (xy 78.74 93.345))
    (stroke (width 0) (type default))
  )
  (wire (pts (xy 104.14 191.77) (xy 118.11 191.77))
    (stroke (width 0) (type default))
  )
  (wire (pts (xy 205.74 181.61) (xy 215.265 181.61))
    (stroke (width 0) (type default))
  )
  (wire (pts (xy 158.75 212.09) (xy 156.21 212.09))
    (stroke (width 0) (type default))
  )
  (wire (pts (xy 383.54 82.55) (xy 383.54 85.09))
    (stroke (width 0) (type default))
  )
  (wire (pts (xy 294.64 38.1) (xy 294.64 39.37))
    (stroke (width 0) (type default))
  )
  (wire (pts (xy 215.265 165.735) (xy 215.265 166.37))
    (stroke (width 0) (type default))
  )
  (wire (pts (xy 76.2 77.47) (xy 90.17 77.47))
    (stroke (width 0) (type default))
  )
  (wire (pts (xy 363.22 85.09) (xy 358.14 85.09))
    (stroke (width 0) (type default))
  )
  (wire (pts (xy 139.7 201.93) (xy 149.86 201.93))
    (stroke (width 0) (type default))
  )
  (wire (pts (xy 102.87 257.81) (xy 102.87 260.35))
    (stroke (width 0) (type default))
  )
  (wire (pts (xy 234.95 260.35) (xy 234.95 262.89))
    (stroke (width 0) (type default))
  )
  (wire (pts (xy 59.69 161.29) (xy 73.66 161.29))
    (stroke (width 0) (type default))
  )
  (wire (pts (xy 223.52 227.33) (xy 215.265 227.33))
    (stroke (width 0) (type default))
  )
  (wire (pts (xy 192.405 240.03) (xy 193.675 240.03))
    (stroke (width 0) (type default))
  )
  (wire (pts (xy 184.15 227.33) (xy 205.74 227.33))
    (stroke (width 0) (type default))
  )
  (wire (pts (xy 104.14 176.53) (xy 118.11 176.53))
    (stroke (width 0) (type default))
  )
  (wire (pts (xy 186.69 240.03) (xy 186.69 245.11))
    (stroke (width 0) (type default))
  )
  (wire (pts (xy 314.325 39.37) (xy 318.77 39.37))
    (stroke (width 0) (type default))
  )
  (wire (pts (xy 367.03 46.99) (xy 367.03 49.53))
    (stroke (width 0) (type default))
  )
  (wire (pts (xy 253.365 227.33) (xy 257.81 227.33))
    (stroke (width 0) (type default))
  )
  (wire (pts (xy 119.38 39.37) (xy 116.84 39.37))
    (stroke (width 0) (type default))
  )
  (wire (pts (xy 237.49 166.37) (xy 240.03 166.37))
    (stroke (width 0) (type default))
  )
  (wire (pts (xy 29.21 77.47) (xy 50.8 77.47))
    (stroke (width 0) (type default))
  )
  (wire (pts (xy 156.21 219.71) (xy 156.21 245.11))
    (stroke (width 0) (type default))
  )
  (wire (pts (xy 253.365 260.35) (xy 257.81 260.35))
    (stroke (width 0) (type default))
  )
  (wire (pts (xy 223.52 189.23) (xy 223.52 191.77))
    (stroke (width 0) (type default))
  )
  (wire (pts (xy 184.15 219.71) (xy 186.69 219.71))
    (stroke (width 0) (type default))
  )
  (wire (pts (xy 205.74 199.39) (xy 184.15 199.39))
    (stroke (width 0) (type default))
  )
  (wire (pts (xy 234.95 267.97) (xy 234.95 270.51))
    (stroke (width 0) (type default))
  )
  (wire (pts (xy 372.11 104.14) (xy 391.16 104.14))
    (stroke (width 0) (type default))
  )
  (wire (pts (xy 215.265 212.09) (xy 223.52 212.09))
    (stroke (width 0) (type default))
  )
  (wire (pts (xy 100.33 52.07) (xy 119.38 52.07))
    (stroke (width 0) (type default))
  )
  (wire (pts (xy 332.74 209.55) (xy 332.74 207.01))
    (stroke (width 0) (type default))
  )
  (wire (pts (xy 184.15 52.705) (xy 186.055 52.705))
    (stroke (width 0) (type default))
  )
  (wire (pts (xy 215.265 196.215) (xy 215.265 196.85))
    (stroke (width 0) (type default))
  )
  (wire (pts (xy 52.07 199.39) (xy 73.66 199.39))
    (stroke (width 0) (type default))
  )
  (wire (pts (xy 223.52 227.33) (xy 234.95 227.33))
    (stroke (width 0) (type default))
  )
  (wire (pts (xy 59.69 168.91) (xy 73.66 168.91))
    (stroke (width 0) (type default))
  )
  (wire (pts (xy 223.52 212.09) (xy 223.52 214.63))
    (stroke (width 0) (type default))
  )
  (wire (pts (xy 332.74 207.01) (xy 334.01 207.01))
    (stroke (width 0) (type default))
  )
  (wire (pts (xy 339.09 39.37) (xy 339.09 41.91))
    (stroke (width 0) (type default))
  )
  (wire (pts (xy 257.81 242.57) (xy 257.81 260.35))
    (stroke (width 0) (type default))
  )
  (wire (pts (xy 149.86 201.93) (xy 158.75 201.93))
    (stroke (width 0) (type default))
  )
  (wire (pts (xy 76.2 74.93) (xy 90.17 74.93))
    (stroke (width 0) (type default))
  )
  (wire (pts (xy 100.33 44.45) (xy 119.38 44.45))
    (stroke (width 0) (type default))
  )
  (wire (pts (xy 363.22 85.09) (xy 363.22 88.9))
    (stroke (width 0) (type default))
  )
  (wire (pts (xy 104.14 156.21) (xy 118.11 156.21))
    (stroke (width 0) (type default))
  )
  (wire (pts (xy 332.74 204.47) (xy 332.74 207.01))
    (stroke (width 0) (type default))
  )
  (wire (pts (xy 76.2 69.85) (xy 90.17 69.85))
    (stroke (width 0) (type default))
  )
  (wire (pts (xy 215.265 180.975) (xy 215.265 181.61))
    (stroke (width 0) (type default))
  )
  (wire (pts (xy 29.21 46.99) (xy 50.8 46.99))
    (stroke (width 0) (type default))
  )
  (wire (pts (xy 378.46 39.37) (xy 384.81 39.37))
    (stroke (width 0) (type default))
  )
  (wire (pts (xy 59.69 173.99) (xy 73.66 173.99))
    (stroke (width 0) (type default))
  )
  (wire (pts (xy 104.14 163.83) (xy 118.11 163.83))
    (stroke (width 0) (type default))
  )
  (wire (pts (xy 205.74 181.61) (xy 205.74 199.39))
    (stroke (width 0) (type default))
  )
  (wire (pts (xy 199.39 237.49) (xy 201.93 237.49))
    (stroke (width 0) (type default))
  )
  (wire (pts (xy 215.265 241.935) (xy 215.265 242.57))
    (stroke (width 0) (type default))
  )
  (wire (pts (xy 100.33 36.83) (xy 119.38 36.83))
    (stroke (width 0) (type default))
  )
  (wire (pts (xy 332.74 173.99) (xy 334.01 173.99))
    (stroke (width 0) (type default))
  )
  (wire (pts (xy 355.6 176.53) (xy 354.33 176.53))
    (stroke (width 0) (type default))
  )
  (wire (pts (xy 186.69 219.71) (xy 186.69 217.17))
    (stroke (width 0) (type default))
  )
  (wire (pts (xy 318.77 39.37) (xy 318.77 41.91))
    (stroke (width 0) (type default))
  )
  (wire (pts (xy 360.68 173.99) (xy 354.33 173.99))
    (stroke (width 0) (type default))
  )
  (wire (pts (xy 237.49 181.61) (xy 240.03 181.61))
    (stroke (width 0) (type default))
  )
  (wire (pts (xy 234.95 250.19) (xy 234.95 252.73))
    (stroke (width 0) (type default))
  )
  (wire (pts (xy 83.82 257.81) (xy 83.82 260.35))
    (stroke (width 0) (type default))
  )
  (wire (pts (xy 209.55 196.85) (xy 209.55 207.01))
    (stroke (width 0) (type default))
  )
  (wire (pts (xy 156.21 214.63) (xy 156.21 219.71))
    (stroke (width 0) (type default))
  )
  (wire (pts (xy 121.92 105.41) (xy 124.46 105.41))
    (stroke (width 0) (type default))
  )
  (wire (pts (xy 223.52 242.57) (xy 223.52 245.11))
    (stroke (width 0) (type default))
  )
  (wire (pts (xy 223.52 181.61) (xy 223.52 184.15))
    (stroke (width 0) (type default))
  )
  (wire (pts (xy 116.84 62.23) (xy 119.38 62.23))
    (stroke (width 0) (type default))
  )
  (wire (pts (xy 90.17 80.01) (xy 90.17 81.28))
    (stroke (width 0) (type default))
  )
  (wire (pts (xy 192.405 240.03) (xy 192.405 246.38))
    (stroke (width 0) (type default))
  )
  (wire (pts (xy 223.52 196.85) (xy 223.52 199.39))
    (stroke (width 0) (type default))
  )
  (wire (pts (xy 334.01 176.53) (xy 332.74 176.53))
    (stroke (width 0) (type default))
  )
  (wire (pts (xy 59.69 156.21) (xy 73.66 156.21))
    (stroke (width 0) (type default))
  )
  (wire (pts (xy 100.33 80.01) (xy 119.38 80.01))
    (stroke (width 0) (type default))
  )
  (wire (pts (xy 360.68 215.9) (xy 360.68 219.71))
    (stroke (width 0) (type default))
  )
  (wire (pts (xy 358.14 99.06) (xy 355.6 99.06))
    (stroke (width 0) (type default))
  )
  (wire (pts (xy 294.64 46.99) (xy 294.64 49.53))
    (stroke (width 0) (type default))
  )
  (wire (pts (xy 105.41 246.38) (xy 102.87 246.38))
    (stroke (width 0) (type default))
  )
  (wire (pts (xy 355.6 209.55) (xy 354.33 209.55))
    (stroke (width 0) (type default))
  )
  (wire (pts (xy 257.81 227.33) (xy 257.81 242.57))
    (stroke (width 0) (type default))
  )
  (wire (pts (xy 104.14 199.39) (xy 106.68 199.39))
    (stroke (width 0) (type default))
  )
  (wire (pts (xy 100.33 41.91) (xy 119.38 41.91))
    (stroke (width 0) (type default))
  )
  (wire (pts (xy 116.84 39.37) (xy 116.84 46.99))
    (stroke (width 0) (type default))
  )
  (wire (pts (xy 59.69 179.07) (xy 73.66 179.07))
    (stroke (width 0) (type default))
  )
  (wire (pts (xy 295.91 104.14) (xy 321.31 104.14))
    (stroke (width 0) (type default))
  )
  (wire (pts (xy 321.31 85.09) (xy 321.31 88.9))
    (stroke (width 0) (type default))
  )
  (wire (pts (xy 215.265 211.455) (xy 215.265 212.09))
    (stroke (width 0) (type default))
  )
  (wire (pts (xy 321.31 93.98) (xy 321.31 104.14))
    (stroke (width 0) (type default))
  )
  (wire (pts (xy 90.17 69.85) (xy 90.17 72.39))
    (stroke (width 0) (type default))
  )
  (wire (pts (xy 184.15 212.09) (xy 215.265 212.09))
    (stroke (width 0) (type default))
  )
  (wire (pts (xy 360.68 182.88) (xy 360.68 186.69))
    (stroke (width 0) (type default))
  )
  (wire (pts (xy 209.55 227.33) (xy 209.55 217.17))
    (stroke (width 0) (type default))
  )
  (wire (pts (xy 332.74 171.45) (xy 332.74 173.99))
    (stroke (width 0) (type default))
  )
  (wire (pts (xy 104.14 171.45) (xy 118.11 171.45))
    (stroke (width 0) (type default))
  )
  (wire (pts (xy 104.14 166.37) (xy 118.11 166.37))
    (stroke (width 0) (type default))
  )
  (wire (pts (xy 330.2 85.09) (xy 330.2 88.9))
    (stroke (width 0) (type default))
  )
  (wire (pts (xy 363.22 101.6) (xy 355.6 101.6))
    (stroke (width 0) (type default))
  )
  (wire (pts (xy 156.21 219.71) (xy 158.75 219.71))
    (stroke (width 0) (type default))
  )
  (wire (pts (xy 223.52 242.57) (xy 234.95 242.57))
    (stroke (width 0) (type default))
  )
  (wire (pts (xy 184.15 207.01) (xy 186.69 207.01))
    (stroke (width 0) (type default))
  )
  (wire (pts (xy 121.92 99.06) (xy 124.46 99.06))
    (stroke (width 0) (type default))
  )
  (wire (pts (xy 372.11 85.09) (xy 363.22 85.09))
    (stroke (width 0) (type default))
  )
  (wire (pts (xy 104.14 179.07) (xy 118.11 179.07))
    (stroke (width 0) (type default))
  )
  (wire (pts (xy 186.055 52.705) (xy 186.055 50.165))
    (stroke (width 0) (type default))
  )
  (wire (pts (xy 332.74 217.17) (xy 332.74 219.71))
    (stroke (width 0) (type default))
  )
  (wire (pts (xy 78.74 82.55) (xy 78.74 85.725))
    (stroke (width 0) (type default))
  )
  (wire (pts (xy 355.6 106.68) (xy 358.14 106.68))
    (stroke (width 0) (type default))
  )
  (wire (pts (xy 201.93 166.37) (xy 215.265 166.37))
    (stroke (width 0) (type default))
  )
  (wire (pts (xy 305.435 85.09) (xy 305.435 87.63))
    (stroke (width 0) (type default))
  )
  (wire (pts (xy 100.33 59.69) (xy 119.38 59.69))
    (stroke (width 0) (type default))
  )
  (wire (pts (xy 383.54 85.09) (xy 372.11 85.09))
    (stroke (width 0) (type default))
  )
  (wire (pts (xy 223.52 166.37) (xy 232.41 166.37))
    (stroke (width 0) (type default))
  )
  (wire (pts (xy 92.71 241.3) (xy 92.71 252.73))
    (stroke (width 0) (type default))
  )
  (wire (pts (xy 332.74 209.55) (xy 332.74 212.09))
    (stroke (width 0) (type default))
  )
  (wire (pts (xy 335.28 99.06) (xy 337.82 99.06))
    (stroke (width 0) (type default))
  )
  (wire (pts (xy 29.21 41.91) (xy 50.8 41.91))
    (stroke (width 0) (type default))
  )
  (wire (pts (xy 237.49 196.85) (xy 240.03 196.85))
    (stroke (width 0) (type default))
  )
  (wire (pts (xy 234.95 212.09) (xy 234.95 214.63))
    (stroke (width 0) (type default))
  )
  (wire (pts (xy 223.52 227.33) (xy 223.52 229.87))
    (stroke (width 0) (type default))
  )
  (wire (pts (xy 332.74 184.15) (xy 332.74 186.69))
    (stroke (width 0) (type default))
  )
  (wire (pts (xy 215.265 166.37) (xy 223.52 166.37))
    (stroke (width 0) (type default))
  )
  (wire (pts (xy 116.84 77.47) (xy 116.84 83.82))
    (stroke (width 0) (type default))
  )
  (wire (pts (xy 337.82 104.14) (xy 321.31 104.14))
    (stroke (width 0) (type default))
  )
  (wire (pts (xy 129.54 99.06) (xy 156.21 99.06))
    (stroke (width 0) (type default))
  )
  (wire (pts (xy 29.21 69.85) (xy 50.8 69.85))
    (stroke (width 0) (type default))
  )
  (wire (pts (xy 240.03 165.1) (xy 240.03 166.37))
    (stroke (width 0) (type default))
  )
  (wire (pts (xy 318.77 46.99) (xy 318.77 49.53))
    (stroke (width 0) (type default))
  )
  (wire (pts (xy 215.265 181.61) (xy 223.52 181.61))
    (stroke (width 0) (type default))
  )
  (wire (pts (xy 100.33 72.39) (xy 119.38 72.39))
    (stroke (width 0) (type default))
  )
  (wire (pts (xy 104.14 105.41) (xy 116.84 105.41))
    (stroke (width 0) (type default))
  )
  (wire (pts (xy 186.69 207.01) (xy 209.55 207.01))
    (stroke (width 0) (type default))
  )
  (wire (pts (xy 234.95 227.33) (xy 248.285 227.33))
    (stroke (width 0) (type default))
  )
  (wire (pts (xy 90.17 74.93) (xy 90.17 77.47))
    (stroke (width 0) (type default))
  )
  (wire (pts (xy 116.84 77.47) (xy 119.38 77.47))
    (stroke (width 0) (type default))
  )
  (wire (pts (xy 384.81 39.37) (xy 398.78 39.37))
    (stroke (width 0) (type default))
  )
  (wire (pts (xy 383.54 85.09) (xy 383.54 87.63))
    (stroke (width 0) (type default))
  )
  (wire (pts (xy 104.14 99.06) (xy 116.84 99.06))
    (stroke (width 0) (type default))
  )
  (wire (pts (xy 104.14 161.29) (xy 118.11 161.29))
    (stroke (width 0) (type default))
  )
  (wire (pts (xy 305.435 92.71) (xy 305.435 95.25))
    (stroke (width 0) (type default))
  )
  (wire (pts (xy 257.81 227.33) (xy 259.08 227.33))
    (stroke (width 0) (type default))
  )
  (wire (pts (xy 367.03 39.37) (xy 367.03 41.91))
    (stroke (width 0) (type default))
  )
  (wire (pts (xy 367.03 39.37) (xy 373.38 39.37))
    (stroke (width 0) (type default))
  )
  (wire (pts (xy 335.28 106.68) (xy 335.28 108.585))
    (stroke (width 0) (type default))
  )
  (wire (pts (xy 104.14 201.93) (xy 106.68 201.93))
    (stroke (width 0) (type default))
  )
  (wire (pts (xy 223.52 181.61) (xy 232.41 181.61))
    (stroke (width 0) (type default))
  )
  (wire (pts (xy 29.21 74.93) (xy 50.8 74.93))
    (stroke (width 0) (type default))
  )
  (wire (pts (xy 328.93 39.37) (xy 328.93 41.91))
    (stroke (width 0) (type default))
  )
  (wire (pts (xy 360.68 207.01) (xy 360.68 210.82))
    (stroke (width 0) (type default))
  )
  (wire (pts (xy 332.74 176.53) (xy 332.74 173.99))
    (stroke (width 0) (type default))
  )
  (wire (pts (xy 151.13 55.245) (xy 167.64 55.245))
    (stroke (width 0) (type default))
  )
  (wire (pts (xy 339.09 39.37) (xy 333.375 39.37))
    (stroke (width 0) (type default))
  )
  (wire (pts (xy 201.93 260.35) (xy 215.265 260.35))
    (stroke (width 0) (type default))
  )
  (wire (pts (xy 209.55 196.85) (xy 215.265 196.85))
    (stroke (width 0) (type default))
  )
  (wire (pts (xy 321.31 85.09) (xy 330.2 85.09))
    (stroke (width 0) (type default))
  )
  (wire (pts (xy 234.95 234.95) (xy 234.95 237.49))
    (stroke (width 0) (type default))
  )
  (wire (pts (xy 234.95 227.33) (xy 234.95 229.87))
    (stroke (width 0) (type default))
  )
  (wire (pts (xy 372.11 93.98) (xy 372.11 104.14))
    (stroke (width 0) (type default))
  )
  (wire (pts (xy 186.69 240.03) (xy 192.405 240.03))
    (stroke (width 0) (type default))
  )
  (wire (pts (xy 29.21 57.15) (xy 50.8 57.15))
    (stroke (width 0) (type default))
  )
  (wire (pts (xy 100.33 57.15) (xy 119.38 57.15))
    (stroke (width 0) (type default))
  )
  (wire (pts (xy 146.05 204.47) (xy 158.75 204.47))
    (stroke (width 0) (type default))
  )
  (wire (pts (xy 340.36 41.91) (xy 339.09 41.91))
    (stroke (width 0) (type default))
  )
  (wire (pts (xy 198.755 240.03) (xy 199.39 240.03))
    (stroke (width 0) (type default))
  )
  (wire (pts (xy 223.52 204.47) (xy 223.52 207.01))
    (stroke (width 0) (type default))
  )
  (wire (pts (xy 92.71 257.81) (xy 92.71 260.35))
    (stroke (width 0) (type default))
  )
  (wire (pts (xy 59.69 163.83) (xy 73.66 163.83))
    (stroke (width 0) (type default))
  )
  (wire (pts (xy 104.14 158.75) (xy 118.11 158.75))
    (stroke (width 0) (type default))
  )
  (wire (pts (xy 304.8 39.37) (xy 294.64 39.37))
    (stroke (width 0) (type default))
  )

  (text "1V2" (at 185.42 217.17 0)
    (effects (font (size 1.27 1.27)) (justify left bottom))
  )
  (text "1V8-3V3" (at 185.42 196.85 0)
    (effects (font (size 1.27 1.27)) (justify left bottom))
  )
  (text "9mA" (at 195.58 199.39 0)
    (effects (font (size 1.27 1.27)) (justify left bottom))
  )
  (text "1V8-3V3" (at 185.42 199.39 0)
    (effects (font (size 1.27 1.27)) (justify left bottom))
  )
  (text "3V3" (at 187.96 207.01 0)
    (effects (font (size 1.27 1.27)) (justify left bottom))
  )
  (text "83mA" (at 190.5 217.17 0)
    (effects (font (size 1.27 1.27)) (justify left bottom))
  )
  (text "Video Interfaces" (at 74.93 143.51 0)
    (effects (font (size 2.54 2.54)) (justify left bottom))
  )
  (text "1.2V" (at 340.36 196.85 0)
    (effects (font (size 3 3)) (justify left bottom))
  )
  (text "13mA" (at 190.5 212.09 0)
    (effects (font (size 1.27 1.27)) (justify left bottom))
  )
  (text "27MHz Oscillator" (at 323.85 25.4 0)
    (effects (font (size 4 4)) (justify left bottom))
  )
  (text "23mA" (at 190.5 227.33 0)
    (effects (font (size 1.27 1.27)) (justify left bottom))
  )
  (text "76mA" (at 190.5 237.49 0)
    (effects (font (size 1.27 1.27)) (justify left bottom))
  )
  (text "Connectors" (at 96.52 25.4 0)
    (effects (font (size 4 4)) (justify left bottom))
  )
  (text "2V5" (at 185.42 212.09 0)
    (effects (font (size 1.27 1.27)) (justify left bottom))
  )
  (text "1V2" (at 185.42 237.49 0)
    (effects (font (size 1.27 1.27)) (justify left bottom))
  )
  (text "1V2" (at 185.42 227.33 0)
    (effects (font (size 1.27 1.27)) (justify left bottom))
  )
  (text "2.5V" (at 340.36 163.83 0)
    (effects (font (size 3 3)) (justify left bottom))
  )
  (text "1V2" (at 185.42 240.03 0)
    (effects (font (size 1.27 1.27)) (justify left bottom))
  )
  (text "CH2_INT" (at 146.05 207.01 0)
    (effects (font (size 1.27 1.27)) (justify left bottom))
  )
  (text "Converter IC" (at 114.3 149.86 0)
    (effects (font (size 4 4)) (justify left bottom))
  )
  (text "Power" (at 166.37 181.61 0)
    (effects (font (size 2.54 2.54)) (justify left bottom))
  )
  (text "Voltage Regulators" (at 317.5 153.67 0)
    (effects (font (size 4 4)) (justify left bottom))
  )
  (text "Misc" (at 104.14 218.44 0)
    (effects (font (size 2.54 2.54)) (justify left bottom))
  )
  (text "I2C Level Shifter" (at 322.58 74.93 0)
    (effects (font (size 4 4)) (justify left bottom))
  )
  (text "88mA" (at 193.04 207.01 0)
    (effects (font (size 1.27 1.27)) (justify left bottom))
  )

  (label "HDMI2_HPD" (at 104.14 99.06 0) (fields_autoplaced)
    (effects (font (size 1.27 1.27)) (justify left bottom))
  )
  (label "HDMI2_DDC_SDA" (at 391.16 104.14 180) (fields_autoplaced)
    (effects (font (size 1.27 1.27)) (justify right bottom))
  )
  (label "HDMI2_D2_N" (at 59.69 173.99 0) (fields_autoplaced)
    (effects (font (size 1.27 1.27)) (justify left bottom))
  )
  (label "HDMI2_DDC_SDA_3V3" (at 52.07 199.39 0) (fields_autoplaced)
    (effects (font (size 1.27 1.27)) (justify left bottom))
  )
  (label "HDMI2_POWER" (at 156.21 99.06 180) (fields_autoplaced)
    (effects (font (size 1.27 1.27)) (justify right bottom))
  )
  (label "HDMI2_HPDO" (at 118.11 184.15 180) (fields_autoplaced)
    (effects (font (size 1.27 1.27)) (justify right bottom))
  )
  (label "HDMI2_DDC_SDA" (at 100.33 74.93 0) (fields_autoplaced)
    (effects (font (size 1.27 1.27)) (justify left bottom))
  )
  (label "HDMI2_CEC" (at 100.33 67.31 0) (fields_autoplaced)
    (effects (font (size 1.27 1.27)) (justify left bottom))
  )
  (label "CH2_REFCLK" (at 146.05 204.47 0) (fields_autoplaced)
    (effects (font (size 1.27 1.27)) (justify left bottom))
  )
  (label "HDMI2_CLK_N" (at 100.33 64.77 0) (fields_autoplaced)
    (effects (font (size 1.27 1.27)) (justify left bottom))
  )
  (label "HDMI2_D0_P" (at 29.21 46.99 0) (fields_autoplaced)
    (effects (font (size 1.27 1.27)) (justify left bottom))
  )
  (label "HDMI2_CLK_N" (at 151.13 70.485 0) (fields_autoplaced)
    (effects (font (size 1.27 1.27)) (justify left bottom))
  )
  (label "HDMI2_CEC" (at 29.21 69.85 0) (fields_autoplaced)
    (effects (font (size 1.27 1.27)) (justify left bottom))
  )
  (label "HDMI2_CLK_N" (at 59.69 158.75 0) (fields_autoplaced)
    (effects (font (size 1.27 1.27)) (justify left bottom))
  )
  (label "HDMI2_DDC_SCL" (at 100.33 72.39 0) (fields_autoplaced)
    (effects (font (size 1.27 1.27)) (justify left bottom))
  )
  (label "HDMI2_D2_N" (at 29.21 34.29 0) (fields_autoplaced)
    (effects (font (size 1.27 1.27)) (justify left bottom))
  )
  (label "CH2_AVDD33" (at 156.21 173.99 270) (fields_autoplaced)
    (effects (font (size 1.27 1.27)) (justify right bottom))
  )
  (label "HDMI2_HPD" (at 100.33 82.55 0) (fields_autoplaced)
    (effects (font (size 1.27 1.27)) (justify left bottom))
  )
  (label "HDMI2_D1_P" (at 151.13 57.785 0) (fields_autoplaced)
    (effects (font (size 1.27 1.27)) (justify left bottom))
  )
  (label "HDMI2_D2_N" (at 151.13 55.245 0) (fields_autoplaced)
    (effects (font (size 1.27 1.27)) (justify left bottom))
  )
  (label "HDMI2_DDC_SCL" (at 29.21 62.23 0) (fields_autoplaced)
    (effects (font (size 1.27 1.27)) (justify left bottom))
  )
  (label "HDMI2_D0_P" (at 59.69 161.29 0) (fields_autoplaced)
    (effects (font (size 1.27 1.27)) (justify left bottom))
  )
  (label "HDMI2_D0_P" (at 151.13 62.865 0) (fields_autoplaced)
    (effects (font (size 1.27 1.27)) (justify left bottom))
  )
  (label "HDMI2_DDC_SDA_3V3" (at 295.91 104.14 0) (fields_autoplaced)
    (effects (font (size 1.27 1.27)) (justify left bottom))
  )
  (label "HDMI2_POWER" (at 29.21 82.55 0) (fields_autoplaced)
    (effects (font (size 1.27 1.27)) (justify left bottom))
  )
  (label "HDMI2_CLK_P" (at 59.69 156.21 0) (fields_autoplaced)
    (effects (font (size 1.27 1.27)) (justify left bottom))
  )
  (label "HDMI2_D0_P" (at 100.33 52.07 0) (fields_autoplaced)
    (effects (font (size 1.27 1.27)) (justify left bottom))
  )
  (label "CH2_AVDD33" (at 186.69 204.47 0) (fields_autoplaced)
    (effects (font (size 1.27 1.27)) (justify left bottom))
  )
  (label "HDMI2_D1_N" (at 100.33 49.53 0) (fields_autoplaced)
    (effects (font (size 1.27 1.27)) (justify left bottom))
  )
  (label "HDMI2_D1_P" (at 59.69 166.37 0) (fields_autoplaced)
    (effects (font (size 1.27 1.27)) (justify left bottom))
  )
  (label "HDMI2_CLK_P" (at 100.33 59.69 0) (fields_autoplaced)
    (effects (font (size 1.27 1.27)) (justify left bottom))
  )
  (label "HDMI2_D1_P" (at 100.33 44.45 0) (fields_autoplaced)
    (effects (font (size 1.27 1.27)) (justify left bottom))
  )
  (label "HDMI2_D1_N" (at 29.21 41.91 0) (fields_autoplaced)
    (effects (font (size 1.27 1.27)) (justify left bottom))
  )
  (label "HDMI2_POWER" (at 100.33 80.01 0) (fields_autoplaced)
    (effects (font (size 1.27 1.27)) (justify left bottom))
  )
  (label "HDMI2_HPDI" (at 104.14 105.41 0) (fields_autoplaced)
    (effects (font (size 1.27 1.27)) (justify left bottom))
  )
  (label "HDMI2_DDC_SCL_3V3" (at 52.07 201.93 0) (fields_autoplaced)
    (effects (font (size 1.27 1.27)) (justify left bottom))
  )
  (label "HDMI2_D0_N" (at 59.69 163.83 0) (fields_autoplaced)
    (effects (font (size 1.27 1.27)) (justify left bottom))
  )
  (label "DUMMY2" (at 29.21 77.47 0) (fields_autoplaced)
    (effects (font (size 1.27 1.27)) (justify left bottom))
  )
  (label "HDMI2_D0_N" (at 100.33 57.15 0) (fields_autoplaced)
    (effects (font (size 1.27 1.27)) (justify left bottom))
  )
  (label "HDMI2_D2_P" (at 151.13 52.705 0) (fields_autoplaced)
    (effects (font (size 1.27 1.27)) (justify left bottom))
  )
  (label "CH2_REFCLK" (at 398.78 39.37 180) (fields_autoplaced)
    (effects (font (size 1.27 1.27)) (justify right bottom))
  )
  (label "HDMI2_D2_N" (at 100.33 41.91 0) (fields_autoplaced)
    (effects (font (size 1.27 1.27)) (justify left bottom))
  )
  (label "HDMI2_D1_N" (at 59.69 168.91 0) (fields_autoplaced)
    (effects (font (size 1.27 1.27)) (justify left bottom))
  )
  (label "HDMI2_CLK_P" (at 151.13 67.945 0) (fields_autoplaced)
    (effects (font (size 1.27 1.27)) (justify left bottom))
  )
  (label "HDMI2_D2_P" (at 29.21 31.75 0) (fields_autoplaced)
    (effects (font (size 1.27 1.27)) (justify left bottom))
  )
  (label "HDMI2_CLK_N" (at 29.21 57.15 0) (fields_autoplaced)
    (effects (font (size 1.27 1.27)) (justify left bottom))
  )
  (label "DUMMY2" (at 100.33 69.85 0) (fields_autoplaced)
    (effects (font (size 1.27 1.27)) (justify left bottom))
  )
  (label "HDMI2_D0_N" (at 151.13 65.405 0) (fields_autoplaced)
    (effects (font (size 1.27 1.27)) (justify left bottom))
  )
  (label "HDMI2_D2_P" (at 100.33 36.83 0) (fields_autoplaced)
    (effects (font (size 1.27 1.27)) (justify left bottom))
  )
  (label "HDMI2_HPD" (at 29.21 74.93 0) (fields_autoplaced)
    (effects (font (size 1.27 1.27)) (justify left bottom))
  )
  (label "HDMI2_D1_N" (at 151.13 60.325 0) (fields_autoplaced)
    (effects (font (size 1.27 1.27)) (justify left bottom))
  )
  (label "HDMI2_DDC_SCL_3V3" (at 295.91 101.6 0) (fields_autoplaced)
    (effects (font (size 1.27 1.27)) (justify left bottom))
  )
  (label "HDMI2_D2_P" (at 59.69 171.45 0) (fields_autoplaced)
    (effects (font (size 1.27 1.27)) (justify left bottom))
  )
  (label "HDMI2_D0_N" (at 29.21 49.53 0) (fields_autoplaced)
    (effects (font (size 1.27 1.27)) (justify left bottom))
  )
  (label "HDMI2_CLK_P" (at 29.21 54.61 0) (fields_autoplaced)
    (effects (font (size 1.27 1.27)) (justify left bottom))
  )
  (label "HDMI2_CEC" (at 59.69 179.07 0) (fields_autoplaced)
    (effects (font (size 1.27 1.27)) (justify left bottom))
  )
  (label "HDMI2_DDC_SCL" (at 391.16 101.6 180) (fields_autoplaced)
    (effects (font (size 1.27 1.27)) (justify right bottom))
  )
  (label "HDMI2_DDC_SDA" (at 29.21 64.77 0) (fields_autoplaced)
    (effects (font (size 1.27 1.27)) (justify left bottom))
  )
  (label "HDMI2_D1_P" (at 29.21 39.37 0) (fields_autoplaced)
    (effects (font (size 1.27 1.27)) (justify left bottom))
  )
  (label "HDMI2_HPDI" (at 59.69 184.15 0) (fields_autoplaced)
    (effects (font (size 1.27 1.27)) (justify left bottom))
  )
  (label "CH2_~{RST}" (at 139.7 201.93 0) (fields_autoplaced)
    (effects (font (size 1.27 1.27)) (justify left bottom))
  )

  (global_label "CSI3_D2_N" (shape input) (at 118.11 168.91 0) (fields_autoplaced)
    (effects (font (size 1.27 1.27)) (justify left))
    (property "Intersheetrefs" "${INTERSHEET_REFS}" (at 130.5621 168.8306 0)
      (effects (font (size 1.27 1.27)) (justify left) hide)
    )
  )
  (global_label "I2C3_SCL" (shape input) (at 118.11 191.77 0) (fields_autoplaced)
    (effects (font (size 1.27 1.27)) (justify left))
    (property "Intersheetrefs" "${INTERSHEET_REFS}" (at 129.2921 191.6906 0)
      (effects (font (size 1.27 1.27)) (justify left) hide)
    )
  )
  (global_label "CSI3_D2_P" (shape input) (at 118.11 166.37 0) (fields_autoplaced)
    (effects (font (size 1.27 1.27)) (justify left))
    (property "Intersheetrefs" "${INTERSHEET_REFS}" (at 130.5017 166.2906 0)
      (effects (font (size 1.27 1.27)) (justify left) hide)
    )
  )
  (global_label "CH2_1V2" (shape input) (at 361.95 207.01 0) (fields_autoplaced)
    (effects (font (size 1.27 1.27)) (justify left))
    (property "Intersheetrefs" "${INTERSHEET_REFS}" (at 372.6483 206.9306 0)
      (effects (font (size 1.27 1.27)) (justify left) hide)
    )
  )
  (global_label "CSI3_D1_P" (shape input) (at 118.11 161.29 0) (fields_autoplaced)
    (effects (font (size 1.27 1.27)) (justify left))
    (property "Intersheetrefs" "${INTERSHEET_REFS}" (at 130.5017 161.2106 0)
      (effects (font (size 1.27 1.27)) (justify left) hide)
    )
  )
  (global_label "CSI3_D3_P" (shape input) (at 118.11 171.45 0) (fields_autoplaced)
    (effects (font (size 1.27 1.27)) (justify left))
    (property "Intersheetrefs" "${INTERSHEET_REFS}" (at 130.5017 171.3706 0)
      (effects (font (size 1.27 1.27)) (justify left) hide)
    )
  )
  (global_label "CSI3_D4_P" (shape input) (at 118.11 176.53 0) (fields_autoplaced)
    (effects (font (size 1.27 1.27)) (justify left))
    (property "Intersheetrefs" "${INTERSHEET_REFS}" (at 130.5017 176.4506 0)
      (effects (font (size 1.27 1.27)) (justify left) hide)
    )
  )
  (global_label "CSI3_D4_N" (shape input) (at 118.11 179.07 0) (fields_autoplaced)
    (effects (font (size 1.27 1.27)) (justify left))
    (property "Intersheetrefs" "${INTERSHEET_REFS}" (at 130.5621 178.9906 0)
      (effects (font (size 1.27 1.27)) (justify left) hide)
    )
  )
  (global_label "CSI3_CLK_P" (shape input) (at 118.11 156.21 0) (fields_autoplaced)
    (effects (font (size 1.27 1.27)) (justify left))
    (property "Intersheetrefs" "${INTERSHEET_REFS}" (at 131.5902 156.1306 0)
      (effects (font (size 1.27 1.27)) (justify left) hide)
    )
  )
  (global_label "CSI3_D3_N" (shape input) (at 118.11 173.99 0) (fields_autoplaced)
    (effects (font (size 1.27 1.27)) (justify left))
    (property "Intersheetrefs" "${INTERSHEET_REFS}" (at 130.5621 173.9106 0)
      (effects (font (size 1.27 1.27)) (justify left) hide)
    )
  )
  (global_label "CSI3_CLK_N" (shape input) (at 118.11 158.75 0) (fields_autoplaced)
    (effects (font (size 1.27 1.27)) (justify left))
    (property "Intersheetrefs" "${INTERSHEET_REFS}" (at 131.6507 158.6706 0)
      (effects (font (size 1.27 1.27)) (justify left) hide)
    )
  )
  (global_label "CH2_2V5" (shape input) (at 361.95 173.99 0) (fields_autoplaced)
    (effects (font (size 1.27 1.27)) (justify left))
    (property "Intersheetrefs" "${INTERSHEET_REFS}" (at 372.6483 173.9106 0)
      (effects (font (size 1.27 1.27)) (justify left) hide)
    )
  )
  (global_label "I2C3_SDA" (shape input) (at 118.11 189.23 0) (fields_autoplaced)
    (effects (font (size 1.27 1.27)) (justify left))
    (property "Intersheetrefs" "${INTERSHEET_REFS}" (at 129.3526 189.1506 0)
      (effects (font (size 1.27 1.27)) (justify left) hide)
    )
  )
  (global_label "CH2_2V5" (shape input) (at 259.08 212.09 0) (fields_autoplaced)
    (effects (font (size 1.27 1.27)) (justify left))
    (property "Intersheetrefs" "${INTERSHEET_REFS}" (at 269.7783 212.0106 0)
      (effects (font (size 1.27 1.27)) (justify left) hide)
    )
  )
  (global_label "CH2_1V2" (shape input) (at 259.08 227.33 0) (fields_autoplaced)
    (effects (font (size 1.27 1.27)) (justify left))
    (property "Intersheetrefs" "${INTERSHEET_REFS}" (at 269.7783 227.2506 0)
      (effects (font (size 1.27 1.27)) (justify left) hide)
    )
  )
  (global_label "CSI3_D1_N" (shape input) (at 118.11 163.83 0) (fields_autoplaced)
    (effects (font (size 1.27 1.27)) (justify left))
    (property "Intersheetrefs" "${INTERSHEET_REFS}" (at 130.5621 163.7506 0)
      (effects (font (size 1.27 1.27)) (justify left) hide)
    )
  )

  (symbol (lib_id "antmicropower:GND") (at 332.74 219.71 0) (unit 1)
    (in_bom yes) (on_board yes) (dnp no)
    (property "Reference" "#PWR0182" (at 332.74 226.06 0)
      (effects (font (size 1.27 1.27)) hide)
    )
    (property "Value" "GND" (at 330.835 224.155 0)
      (effects (font (size 1.27 1.27) (thickness 0.15)) (justify left bottom))
    )
    (property "Footprint" "" (at 332.74 219.71 0)
      (effects (font (size 1.27 1.27) (thickness 0.15)) (justify left bottom) hide)
    )
    (property "Datasheet" "" (at 332.74 219.71 0)
      (effects (font (size 1.27 1.27) (thickness 0.15)) (justify left bottom) hide)
    )
    (property "Author" "Antmicro" (at 341.63 227.33 0)
      (effects (font (size 1.27 1.27) (thickness 0.15)) (justify left bottom) hide)
    )
    (property "License" "Apache-2.0" (at 341.63 229.87 0)
      (effects (font (size 1.27 1.27) (thickness 0.15)) (justify left bottom) hide)
    )
    (pin "1")
    (instances
      (project "antmicro-hdmi-mipi-bridge-hw"
        (path ""
          (reference "#PWR0182") (unit 1)
        )
      )
    )
  )

  (symbol (lib_id "antmicropower:GND") (at 186.055 73.025 0) (unit 1)
    (in_bom yes) (on_board yes) (dnp no)
    (property "Reference" "#PWR0147" (at 186.055 79.375 0)
      (effects (font (size 1.27 1.27)) hide)
    )
    (property "Value" "GND" (at 184.15 77.47 0)
      (effects (font (size 1.27 1.27) (thickness 0.15)) (justify left bottom))
    )
    (property "Footprint" "" (at 186.055 73.025 0)
      (effects (font (size 1.27 1.27) (thickness 0.15)) (justify left bottom) hide)
    )
    (property "Datasheet" "" (at 186.055 73.025 0)
      (effects (font (size 1.27 1.27) (thickness 0.15)) (justify left bottom) hide)
    )
    (property "Author" "Antmicro" (at 194.945 80.645 0)
      (effects (font (size 1.27 1.27) (thickness 0.15)) (justify left bottom) hide)
    )
    (property "License" "Apache-2.0" (at 194.945 83.185 0)
      (effects (font (size 1.27 1.27) (thickness 0.15)) (justify left bottom) hide)
    )
    (pin "1")
    (instances
      (project "antmicro-hdmi-mipi-bridge-hw"
        (path ""
          (reference "#PWR0147") (unit 1)
        )
      )
    )
  )

  (symbol (lib_id "antmicropower:PWR_FLAG") (at 129.54 98.425 0) (unit 1)
    (in_bom yes) (on_board yes) (dnp no)
    (property "Reference" "#FLG0123" (at 129.54 96.52 0)
      (effects (font (size 1.27 1.27)) hide)
    )
    (property "Value" "PWR_FLAG" (at 124.46 94.615 0)
      (effects (font (size 1.27 1.27)) (justify left))
    )
    (property "Footprint" "" (at 129.54 98.425 0)
      (effects (font (size 1.27 1.27)) hide)
    )
    (property "Datasheet" "" (at 129.54 98.425 0)
      (effects (font (size 1.27 1.27)) hide)
    )
    (pin "1")
    (instances
      (project "antmicro-hdmi-mipi-bridge-hw"
        (path ""
          (reference "#FLG0123") (unit 1)
        )
      )
    )
  )

  (symbol (lib_id "antmicroFerriteBeadsandChips:FB_600Z_0.5A_Murata-BLM18AG_0603") (at 309.245 39.37 0) (unit 1)
    (in_bom yes) (on_board yes) (dnp no)
    (property "Reference" "FB12" (at 312.42 33.02 0)
      (effects (font (size 1.524 1.524)))
    )
    (property "Value" "FB_600Z_0.5A_Murata-BLM18AG_0603" (at 324.485 41.91 0)
      (effects (font (size 1.27 1.27) (thickness 0.15)) (justify left bottom) hide)
    )
    (property "Footprint" "antmicro-footprints:FB_0603_1608Metric" (at 324.485 46.99 0)
      (effects (font (size 1.27 1.27) (thickness 0.15)) (justify left bottom) hide)
    )
    (property "Datasheet" "https://www.murata.com/en-us/products/productdata/8796738650142/ENFA0003.pdf" (at 324.485 49.53 0)
      (effects (font (size 1.27 1.27) (thickness 0.15)) (justify left bottom) hide)
    )
    (property "MPN" "BLM18AG601SN1D" (at 324.485 52.07 0)
      (effects (font (size 1.27 1.27) (thickness 0.15)) (justify left bottom) hide)
    )
    (property "Manufacturer" "Murata" (at 324.485 54.61 0)
      (effects (font (size 1.27 1.27) (thickness 0.15)) (justify left bottom) hide)
    )
    (property "Author" "Antmicro" (at 324.485 57.15 0)
      (effects (font (size 1.27 1.27) (thickness 0.15)) (justify left bottom) hide)
    )
    (property "License" "Apache-2.0" (at 324.485 59.69 0)
      (effects (font (size 1.27 1.27) (thickness 0.15)) (justify left bottom) hide)
    )
    (property "Val" "600Z/0.5A" (at 307.34 36.83 0)
      (effects (font (size 1.27 1.27)) (justify left bottom))
    )
    (property "Current" "" (at 329.565 62.23 0)
      (effects (font (size 1.27 1.27) (thickness 0.15)) (justify left bottom) hide)
    )
    (property "Public" "False" (at 329.565 54.61 0)
      (effects (font (size 1.27 1.27)) (justify left bottom) hide)
    )
    (pin "1")
    (pin "2")
    (instances
      (project "antmicro-hdmi-mipi-bridge-hw"
        (path ""
          (reference "FB12") (unit 1)
        )
      )
    )
  )

  (symbol (lib_id "antmicropower:GND") (at 223.52 191.77 0) (unit 1)
    (in_bom yes) (on_board yes) (dnp no)
    (property "Reference" "#PWR0191" (at 223.52 198.12 0)
      (effects (font (size 1.27 1.27)) hide)
    )
    (property "Value" "GND" (at 225.425 194.31 0)
      (effects (font (size 1.27 1.27) (thickness 0.15)) (justify left bottom))
    )
    (property "Footprint" "" (at 223.52 191.77 0)
      (effects (font (size 1.27 1.27) (thickness 0.15)) (justify left bottom) hide)
    )
    (property "Datasheet" "" (at 223.52 191.77 0)
      (effects (font (size 1.27 1.27) (thickness 0.15)) (justify left bottom) hide)
    )
    (property "Author" "Antmicro" (at 232.41 199.39 0)
      (effects (font (size 1.27 1.27) (thickness 0.15)) (justify left bottom) hide)
    )
    (property "License" "Apache-2.0" (at 232.41 201.93 0)
      (effects (font (size 1.27 1.27) (thickness 0.15)) (justify left bottom) hide)
    )
    (pin "1")
    (instances
      (project "antmicro-hdmi-mipi-bridge-hw"
        (path ""
          (reference "#PWR0191") (unit 1)
        )
      )
    )
  )

  (symbol (lib_id "antmicropower:GND") (at 234.95 252.73 0) (unit 1)
    (in_bom yes) (on_board yes) (dnp no)
    (property "Reference" "#PWR0184" (at 234.95 259.08 0)
      (effects (font (size 1.27 1.27)) hide)
    )
    (property "Value" "GND" (at 233.045 257.81 0)
      (effects (font (size 1.27 1.27) (thickness 0.15)) (justify left bottom))
    )
    (property "Footprint" "" (at 234.95 252.73 0)
      (effects (font (size 1.27 1.27) (thickness 0.15)) (justify left bottom) hide)
    )
    (property "Datasheet" "" (at 234.95 252.73 0)
      (effects (font (size 1.27 1.27) (thickness 0.15)) (justify left bottom) hide)
    )
    (property "Author" "Antmicro" (at 243.84 260.35 0)
      (effects (font (size 1.27 1.27) (thickness 0.15)) (justify left bottom) hide)
    )
    (property "License" "Apache-2.0" (at 243.84 262.89 0)
      (effects (font (size 1.27 1.27) (thickness 0.15)) (justify left bottom) hide)
    )
    (pin "1")
    (instances
      (project "antmicro-hdmi-mipi-bridge-hw"
        (path ""
          (reference "#PWR0184") (unit 1)
        )
      )
    )
  )

  (symbol (lib_id "antmicroTestPoints:TP_0.75mm_SMD") (at 118.11 184.15 0) (unit 1)
    (in_bom no) (on_board yes) (dnp no) (fields_autoplaced)
    (property "Reference" "TP7" (at 123.19 184.1499 0)
      (effects (font (size 1.27 1.27)) (justify left))
    )
    (property "Value" "TP_0.75mm_SMD" (at 133.35 191.77 0)
      (effects (font (size 1.27 1.27) (thickness 0.15)) (justify left bottom) hide)
    )
    (property "Footprint" "antmicro-footprints:TP_SMD_0.75mm" (at 133.35 194.31 0)
      (effects (font (size 1.27 1.27) (thickness 0.15)) (justify left bottom) hide)
    )
    (property "Datasheet" "" (at 133.35 196.85 0)
      (effects (font (size 1.27 1.27) (thickness 0.15)) (justify left bottom) hide)
    )
    (property "MPN" "" (at 118.11 184.15 0)
      (effects (font (size 1.27 1.27) (thickness 0.15)) (justify left bottom) hide)
    )
    (property "Manufacturer" "" (at 118.11 184.15 0)
      (effects (font (size 1.27 1.27) (thickness 0.15)) (justify left bottom) hide)
    )
    (property "Author" "Antmicro" (at 133.35 199.39 0)
      (effects (font (size 1.27 1.27) (thickness 0.15)) (justify left bottom) hide)
    )
    (property "License" "Apache-2.0" (at 133.35 201.93 0)
      (effects (font (size 1.27 1.27) (thickness 0.15)) (justify left bottom) hide)
    )
    (property "Public" "False" (at 128.27 198.12 0)
      (effects (font (size 1.27 1.27)) (justify left bottom) hide)
    )
    (pin "1")
    (instances
      (project "antmicro-hdmi-mipi-bridge-hw"
        (path ""
          (reference "TP7") (unit 1)
        )
      )
    )
  )

  (symbol (lib_id "antmicropower:PWR_FLAG") (at 333.375 38.735 0) (unit 1)
    (in_bom yes) (on_board yes) (dnp no)
    (property "Reference" "#FLG0121" (at 333.375 36.83 0)
      (effects (font (size 1.27 1.27)) hide)
    )
    (property "Value" "PWR_FLAG" (at 328.295 34.925 0)
      (effects (font (size 1.27 1.27)) (justify left))
    )
    (property "Footprint" "" (at 333.375 38.735 0)
      (effects (font (size 1.27 1.27)) hide)
    )
    (property "Datasheet" "" (at 333.375 38.735 0)
      (effects (font (size 1.27 1.27)) hide)
    )
    (pin "1")
    (instances
      (project "antmicro-hdmi-mipi-bridge-hw"
        (path ""
          (reference "#FLG0121") (unit 1)
        )
      )
    )
  )

  (symbol (lib_id "antmicropower:GND") (at 83.82 260.35 0) (unit 1)
    (in_bom yes) (on_board yes) (dnp no)
    (property "Reference" "#PWR0153" (at 83.82 266.7 0)
      (effects (font (size 1.27 1.27)) hide)
    )
    (property "Value" "GND" (at 81.915 265.43 0)
      (effects (font (size 1.27 1.27) (thickness 0.15)) (justify left bottom))
    )
    (property "Footprint" "" (at 83.82 260.35 0)
      (effects (font (size 1.27 1.27) (thickness 0.15)) (justify left bottom) hide)
    )
    (property "Datasheet" "" (at 83.82 260.35 0)
      (effects (font (size 1.27 1.27) (thickness 0.15)) (justify left bottom) hide)
    )
    (property "Author" "Antmicro" (at 92.71 267.97 0)
      (effects (font (size 1.27 1.27) (thickness 0.15)) (justify left bottom) hide)
    )
    (property "License" "Apache-2.0" (at 92.71 270.51 0)
      (effects (font (size 1.27 1.27) (thickness 0.15)) (justify left bottom) hide)
    )
    (pin "1")
    (instances
      (project "antmicro-hdmi-mipi-bridge-hw"
        (path ""
          (reference "#PWR0153") (unit 1)
        )
      )
    )
  )

  (symbol (lib_id "antmicroCapacitors0402:C_100n_0402") (at 83.82 257.81 90) (unit 1)
    (in_bom yes) (on_board yes) (dnp no)
    (property "Reference" "C24" (at 81.28 254.635 90)
      (effects (font (size 1.524 1.524)) (justify left))
    )
    (property "Value" "C_100n_0402" (at 93.98 237.49 0)
      (effects (font (size 1.27 1.27) (thickness 0.15)) (justify left bottom) hide)
    )
    (property "Footprint" "antmicro-footprints:C_0402_1005Metric" (at 96.52 237.49 0)
      (effects (font (size 1.27 1.27) (thickness 0.15)) (justify left bottom) hide)
    )
    (property "Datasheet" "https://www.murata.com/products/productdetail?partno=GRM155R61H104KE14%23" (at 99.06 237.49 0)
      (effects (font (size 1.27 1.27) (thickness 0.15)) (justify left bottom) hide)
    )
    (property "Manufacturer" "Murata" (at 104.14 237.49 0)
      (effects (font (size 1.27 1.27) (thickness 0.15)) (justify left bottom) hide)
    )
    (property "MPN" "GRM155R61H104KE14D" (at 101.6 237.49 0)
      (effects (font (size 1.27 1.27) (thickness 0.15)) (justify left bottom) hide)
    )
    (property "Val" "100n" (at 81.915 255.905 90)
      (effects (font (size 1.27 1.27) (thickness 0.15)) (justify left bottom))
    )
    (property "License" "Apache-2.0" (at 106.68 237.49 0)
      (effects (font (size 1.27 1.27) (thickness 0.15)) (justify left bottom) hide)
    )
    (property "Author" "Antmicro" (at 109.22 237.49 0)
      (effects (font (size 1.27 1.27) (thickness 0.15)) (justify left bottom) hide)
    )
    (property "Voltage" "50V" (at 111.76 237.49 0)
      (effects (font (size 1.27 1.27)) (justify left bottom) hide)
    )
    (property "Dielectric" "X5R" (at 114.3 237.49 0)
      (effects (font (size 1.27 1.27)) (justify left bottom) hide)
    )
    (property "Public" "False" (at 116.84 237.49 0)
      (effects (font (size 1.27 1.27)) (justify left bottom) hide)
    )
    (pin "1")
    (pin "2")
    (instances
      (project "antmicro-hdmi-mipi-bridge-hw"
        (path ""
          (reference "C24") (unit 1)
        )
      )
    )
  )

  (symbol (lib_id "antmicroCapacitors0402:C_47p_0402") (at 304.8 46.99 90) (unit 1)
    (in_bom yes) (on_board yes) (dnp no)
    (property "Reference" "C36" (at 311.785 43.18 90)
      (effects (font (size 1.524 1.524)) (justify left))
    )
    (property "Value" "C_47p_0402" (at 314.96 26.67 0)
      (effects (font (size 1.27 1.27) (thickness 0.15)) (justify left bottom) hide)
    )
    (property "Footprint" "antmicro-footprints:C_0402_1005Metric" (at 317.5 26.67 0)
      (effects (font (size 1.27 1.27) (thickness 0.15)) (justify left bottom) hide)
    )
    (property "Datasheet" "https://www.kemet.com/en/us/capacitors/product/C0402C470J5GACTU.html" (at 320.04 26.67 0)
      (effects (font (size 1.27 1.27) (thickness 0.15)) (justify left bottom) hide)
    )
    (property "Manufacturer" "KEMET" (at 325.12 26.67 0)
      (effects (font (size 1.27 1.27) (thickness 0.15)) (justify left bottom) hide)
    )
    (property "MPN" "C0402C470J5GACTU" (at 322.58 26.67 0)
      (effects (font (size 1.27 1.27) (thickness 0.15)) (justify left bottom) hide)
    )
    (property "Val" "47p" (at 311.15 44.45 90)
      (effects (font (size 1.27 1.27) (thickness 0.15)) (justify left bottom))
    )
    (property "License" "Apache-2.0" (at 327.66 26.67 0)
      (effects (font (size 1.27 1.27) (thickness 0.15)) (justify left bottom) hide)
    )
    (property "Author" "Antmicro" (at 330.2 26.67 0)
      (effects (font (size 1.27 1.27) (thickness 0.15)) (justify left bottom) hide)
    )
    (property "Voltage" "" (at 332.74 26.67 0)
      (effects (font (size 1.27 1.27)) (justify left bottom) hide)
    )
    (property "Dielectric" "C0G" (at 335.28 26.67 0)
      (effects (font (size 1.27 1.27)) (justify left bottom) hide)
    )
    (property "Public" "False" (at 337.82 26.67 0)
      (effects (font (size 1.27 1.27)) (justify left bottom) hide)
    )
    (pin "1")
    (pin "2")
    (instances
      (project "antmicro-hdmi-mipi-bridge-hw"
        (path ""
          (reference "C36") (unit 1)
        )
      )
    )
  )

  (symbol (lib_id "antmicroCapacitors0402:C_100n_0402") (at 223.52 189.23 90) (unit 1)
    (in_bom yes) (on_board yes) (dnp no) (fields_autoplaced)
    (property "Reference" "C33" (at 226.06 185.4136 90)
      (effects (font (size 1.524 1.524)) (justify right))
    )
    (property "Value" "C_100n_0402" (at 233.68 168.91 0)
      (effects (font (size 1.27 1.27) (thickness 0.15)) (justify left bottom) hide)
    )
    (property "Footprint" "antmicro-footprints:C_0402_1005Metric" (at 236.22 168.91 0)
      (effects (font (size 1.27 1.27) (thickness 0.15)) (justify left bottom) hide)
    )
    (property "Datasheet" "https://www.murata.com/products/productdetail?partno=GRM155R61H104KE14%23" (at 238.76 168.91 0)
      (effects (font (size 1.27 1.27) (thickness 0.15)) (justify left bottom) hide)
    )
    (property "Manufacturer" "Murata" (at 243.84 168.91 0)
      (effects (font (size 1.27 1.27) (thickness 0.15)) (justify left bottom) hide)
    )
    (property "MPN" "GRM155R61H104KE14D" (at 241.3 168.91 0)
      (effects (font (size 1.27 1.27) (thickness 0.15)) (justify left bottom) hide)
    )
    (property "Val" "100n" (at 226.06 187.9536 90)
      (effects (font (size 1.27 1.27) (thickness 0.15)) (justify right))
    )
    (property "License" "Apache-2.0" (at 246.38 168.91 0)
      (effects (font (size 1.27 1.27) (thickness 0.15)) (justify left bottom) hide)
    )
    (property "Author" "Antmicro" (at 248.92 168.91 0)
      (effects (font (size 1.27 1.27) (thickness 0.15)) (justify left bottom) hide)
    )
    (property "Voltage" "50V" (at 251.46 168.91 0)
      (effects (font (size 1.27 1.27)) (justify left bottom) hide)
    )
    (property "Dielectric" "X5R" (at 254 168.91 0)
      (effects (font (size 1.27 1.27)) (justify left bottom) hide)
    )
    (property "Public" "False" (at 256.54 168.91 0)
      (effects (font (size 1.27 1.27)) (justify left bottom) hide)
    )
    (pin "1")
    (pin "2")
    (instances
      (project "antmicro-hdmi-mipi-bridge-hw"
        (path ""
          (reference "C33") (unit 1)
        )
      )
    )
  )

  (symbol (lib_id "antmicropower:+3V3") (at 186.055 50.165 0) (unit 1)
    (in_bom yes) (on_board yes) (dnp no)
    (property "Reference" "#PWR0145" (at 186.055 53.975 0)
      (effects (font (size 1.27 1.27)) hide)
    )
    (property "Value" "+3V3" (at 182.88 46.99 0)
      (effects (font (size 1.27 1.27) (thickness 0.15)) (justify left bottom))
    )
    (property "Footprint" "" (at 186.055 50.165 0)
      (effects (font (size 1.27 1.27) (thickness 0.15)) (justify left bottom) hide)
    )
    (property "Datasheet" "" (at 186.055 50.165 0)
      (effects (font (size 1.27 1.27) (thickness 0.15)) (justify left bottom) hide)
    )
    (property "Author" "Antmicro" (at 201.295 52.705 0)
      (effects (font (size 1.27 1.27) (thickness 0.15)) (justify left bottom) hide)
    )
    (property "License" "Apache-2.0" (at 201.295 55.245 0)
      (effects (font (size 1.27 1.27) (thickness 0.15)) (justify left bottom) hide)
    )
    (pin "1")
    (instances
      (project "antmicro-hdmi-mipi-bridge-hw"
        (path ""
          (reference "#PWR0145") (unit 1)
        )
      )
    )
  )

  (symbol (lib_id "antmicroResistors0603:R_0R_0603") (at 121.92 105.41 180) (unit 1)
    (in_bom yes) (on_board yes) (dnp no)
    (property "Reference" "R15" (at 119.38 107.95 0)
      (effects (font (size 1.524 1.524)))
    )
    (property "Value" "R_0R_0603" (at 101.6 92.71 0)
      (effects (font (size 1.27 1.27) (thickness 0.15)) (justify left bottom) hide)
    )
    (property "Footprint" "antmicro-footprints:R_0603_1608Metric" (at 101.6 90.17 0)
      (effects (font (size 1.27 1.27) (thickness 0.15)) (justify left bottom) hide)
    )
    (property "Datasheet" "https://www.bourns.com/docs/product-datasheets/cr.pdf?sfvrsn=574d41f6_14" (at 101.6 87.63 0)
      (effects (font (size 1.27 1.27) (thickness 0.15)) (justify left bottom) hide)
    )
    (property "Manufacturer" "Bourns" (at 101.6 82.55 0)
      (effects (font (size 1.27 1.27) (thickness 0.15)) (justify left bottom) hide)
    )
    (property "MPN" "CR0603-J/-000ELF" (at 101.6 85.09 0)
      (effects (font (size 1.27 1.27) (thickness 0.15)) (justify left bottom) hide)
    )
    (property "Val" "0R" (at 120.65 109.22 0)
      (effects (font (size 1.27 1.27) (thickness 0.15)) (justify left bottom))
    )
    (property "License" "Apache-2.0" (at 101.6 80.01 0)
      (effects (font (size 1.27 1.27) (thickness 0.15)) (justify left bottom) hide)
    )
    (property "Author" "Antmicro" (at 101.6 77.47 0)
      (effects (font (size 1.27 1.27) (thickness 0.15)) (justify left bottom) hide)
    )
    (property "Tolerance" "~" (at 101.6 95.25 0)
      (effects (font (size 1.27 1.27)) (justify left bottom) hide)
    )
    (property "Current" "1A" (at 101.6 74.93 0)
      (effects (font (size 1.27 1.27) (thickness 0.15)) (justify left bottom) hide)
    )
    (property "Public" "False" (at 101.6 74.93 0)
      (effects (font (size 1.27 1.27)) (justify left bottom) hide)
    )
    (pin "1")
    (pin "2")
    (instances
      (project "antmicro-hdmi-mipi-bridge-hw"
        (path ""
          (reference "R15") (unit 1)
        )
      )
    )
  )

  (symbol (lib_id "antmicropower:GND") (at 318.77 49.53 0) (unit 1)
    (in_bom yes) (on_board yes) (dnp no)
    (property "Reference" "#PWR0172" (at 318.77 55.88 0)
      (effects (font (size 1.27 1.27)) hide)
    )
    (property "Value" "GND" (at 316.865 53.975 0)
      (effects (font (size 1.27 1.27) (thickness 0.15)) (justify left bottom))
    )
    (property "Footprint" "" (at 318.77 49.53 0)
      (effects (font (size 1.27 1.27) (thickness 0.15)) (justify left bottom) hide)
    )
    (property "Datasheet" "" (at 318.77 49.53 0)
      (effects (font (size 1.27 1.27) (thickness 0.15)) (justify left bottom) hide)
    )
    (property "Author" "Antmicro" (at 327.66 57.15 0)
      (effects (font (size 1.27 1.27) (thickness 0.15)) (justify left bottom) hide)
    )
    (property "License" "Apache-2.0" (at 327.66 59.69 0)
      (effects (font (size 1.27 1.27) (thickness 0.15)) (justify left bottom) hide)
    )
    (pin "1")
    (instances
      (project "antmicro-hdmi-mipi-bridge-hw"
        (path ""
          (reference "#PWR0172") (unit 1)
        )
      )
    )
  )

  (symbol (lib_id "antmicroCapacitors0603:C_4u7_0603") (at 234.95 250.19 90) (unit 1)
    (in_bom yes) (on_board yes) (dnp no) (fields_autoplaced)
    (property "Reference" "C53" (at 237.49 246.3736 90)
      (effects (font (size 1.524 1.524)) (justify right))
    )
    (property "Value" "C_4u7_0603" (at 245.11 229.87 0)
      (effects (font (size 1.27 1.27) (thickness 0.15)) (justify left bottom) hide)
    )
    (property "Footprint" "antmicro-footprints:C_0603_1608Metric" (at 247.65 229.87 0)
      (effects (font (size 1.27 1.27) (thickness 0.15)) (justify left bottom) hide)
    )
    (property "Datasheet" "https://product.tdk.com/en/search/capacitor/ceramic/mlcc/info?part_no=C1608X5R1V475M080AC" (at 250.19 229.87 0)
      (effects (font (size 1.27 1.27) (thickness 0.15)) (justify left bottom) hide)
    )
    (property "Manufacturer" "TDK" (at 255.27 229.87 0)
      (effects (font (size 1.27 1.27) (thickness 0.15)) (justify left bottom) hide)
    )
    (property "MPN" "C1608X5R1V475M080AC" (at 252.73 229.87 0)
      (effects (font (size 1.27 1.27) (thickness 0.15)) (justify left bottom) hide)
    )
    (property "Val" "4u7" (at 237.49 248.9136 90)
      (effects (font (size 1.27 1.27) (thickness 0.15)) (justify right))
    )
    (property "License" "Apache-2.0" (at 257.81 229.87 0)
      (effects (font (size 1.27 1.27) (thickness 0.15)) (justify left bottom) hide)
    )
    (property "Author" "Antmicro" (at 260.35 229.87 0)
      (effects (font (size 1.27 1.27) (thickness 0.15)) (justify left bottom) hide)
    )
    (property "Voltage" "" (at 262.89 229.87 0)
      (effects (font (size 1.27 1.27)) (justify left bottom) hide)
    )
    (property "Dielectric" "" (at 265.43 229.87 0)
      (effects (font (size 1.27 1.27)) (justify left bottom) hide)
    )
    (property "Public" "False" (at 267.97 229.87 0)
      (effects (font (size 1.27 1.27)) (justify left bottom) hide)
    )
    (pin "1")
    (pin "2")
    (instances
      (project "antmicro-hdmi-mipi-bridge-hw"
        (path ""
          (reference "C53") (unit 1)
        )
      )
    )
  )

  (symbol (lib_id "antmicroFerriteBeadsandChips:FB_1kZ_0.8A_WE-CBF_0805") (at 248.285 227.33 0) (unit 1)
    (in_bom yes) (on_board yes) (dnp no)
    (property "Reference" "FB9" (at 250.825 222.25 0)
      (effects (font (size 1.524 1.524)))
    )
    (property "Value" "FB_1kZ_0.8A_WE-CBF_0805" (at 263.525 235.458 0)
      (effects (font (size 1.27 1.27) (thickness 0.15)) (justify left bottom) hide)
    )
    (property "Footprint" "antmicro-footprints:FB_0805_2012Metric" (at 263.525 237.998 0)
      (effects (font (size 1.27 1.27) (thickness 0.15)) (justify left bottom) hide)
    )
    (property "Datasheet" "https://www.we-online.com/components/products/datasheet/742792096.pdf" (at 263.525 240.538 0)
      (effects (font (size 1.27 1.27) (thickness 0.15)) (justify left bottom) hide)
    )
    (property "MPN" "742792096" (at 263.525 229.87 0)
      (effects (font (size 1.27 1.27) (thickness 0.15)) (justify left bottom) hide)
    )
    (property "Manufacturer" "Würth Elektronik" (at 263.525 243.078 0)
      (effects (font (size 1.27 1.27) (thickness 0.15)) (justify left bottom) hide)
    )
    (property "Author" "Antmicro" (at 263.525 245.618 0)
      (effects (font (size 1.27 1.27) (thickness 0.15)) (justify left bottom) hide)
    )
    (property "License" "Apache-2.0" (at 263.525 248.158 0)
      (effects (font (size 1.27 1.27) (thickness 0.15)) (justify left bottom) hide)
    )
    (property "Val" "1kZ/0.8A" (at 246.38 225.425 0)
      (effects (font (size 1.27 1.27)) (justify left bottom))
    )
    (property "Current" "" (at 268.605 250.19 0)
      (effects (font (size 1.27 1.27) (thickness 0.15)) (justify left bottom) hide)
    )
    (property "Public" "False" (at 268.605 242.57 0)
      (effects (font (size 1.27 1.27)) (justify left bottom) hide)
    )
    (pin "1")
    (pin "2")
    (instances
      (project "antmicro-hdmi-mipi-bridge-hw"
        (path ""
          (reference "FB9") (unit 1)
        )
      )
    )
  )

  (symbol (lib_id "antmicroFCCConnectors:5051101992") (at 119.38 36.83 0) (unit 1)
    (in_bom no) (on_board no) (dnp yes)
    (property "Reference" "J5" (at 123.19 30.48 0)
      (effects (font (size 1.27 1.27)) (justify left))
    )
    (property "Value" "5051101992" (at 118.745 33.655 0)
      (effects (font (size 1.27 1.27) (thickness 0.15)) (justify left bottom) hide)
    )
    (property "Footprint" "antmicro-footprints:5051101992" (at 142.24 46.99 0)
      (effects (font (size 1.27 1.27) (thickness 0.15)) (justify left bottom) hide)
    )
    (property "Datasheet" "https://www.molex.com/webdocs/datasheets/pdf/en-us/5051101992_FFC_FPC_CONNECTORS.pdf" (at 142.24 49.53 0)
      (effects (font (size 1.27 1.27) (thickness 0.15)) (justify left bottom) hide)
    )
    (property "Manufacturer" "Molex" (at 142.24 52.07 0)
      (effects (font (size 1.27 1.27) (thickness 0.15)) (justify left bottom) hide)
    )
    (property "MPN" "5051101992" (at 118.745 33.655 0)
      (effects (font (size 1.27 1.27) (thickness 0.15)) (justify left bottom))
    )
    (property "Author" "Antmicro" (at 142.24 57.15 0)
      (effects (font (size 1.27 1.27) (thickness 0.15)) (justify left bottom) hide)
    )
    (property "License" "Apache-2.0" (at 142.24 59.69 0)
      (effects (font (size 1.27 1.27) (thickness 0.15)) (justify left bottom) hide)
    )
    (property "DNP" "DNP" (at 0 0 0)
      (effects (font (size 1 1)))
    )
    (pin "1")
    (pin "10")
    (pin "11")
    (pin "12")
    (pin "13")
    (pin "14")
    (pin "15")
    (pin "16")
    (pin "17")
    (pin "18")
    (pin "19")
    (pin "2")
    (pin "3")
    (pin "4")
    (pin "5")
    (pin "6")
    (pin "7")
    (pin "8")
    (pin "9")
    (instances
      (project "antmicro-hdmi-mipi-bridge-hw"
        (path ""
          (reference "J5") (unit 1)
        )
      )
    )
  )

  (symbol (lib_id "antmicroCapacitors0603:C_10u_0603") (at 332.74 217.17 90) (unit 1)
    (in_bom yes) (on_board yes) (dnp no)
    (property "Reference" "C41" (at 339.09 217.17 90)
      (effects (font (size 1.524 1.524)) (justify left))
    )
    (property "Value" "C_10u_0603" (at 342.9 196.85 0)
      (effects (font (size 1.27 1.27) (thickness 0.15)) (justify left bottom) hide)
    )
    (property "Footprint" "antmicro-footprints:C_0603_1608Metric" (at 345.44 196.85 0)
      (effects (font (size 1.27 1.27) (thickness 0.15)) (justify left bottom) hide)
    )
    (property "Datasheet" "https://www.murata.com/products/productdetail?partno=GRM188R61A106KE69%23" (at 347.98 196.85 0)
      (effects (font (size 1.27 1.27) (thickness 0.15)) (justify left bottom) hide)
    )
    (property "Manufacturer" "Murata" (at 353.06 196.85 0)
      (effects (font (size 1.27 1.27) (thickness 0.15)) (justify left bottom) hide)
    )
    (property "MPN" "GRM188R61A106KE69D" (at 350.52 196.85 0)
      (effects (font (size 1.27 1.27) (thickness 0.15)) (justify left bottom) hide)
    )
    (property "Val" "10u" (at 338.455 218.44 90)
      (effects (font (size 1.27 1.27) (thickness 0.15)) (justify left bottom))
    )
    (property "License" "Apache-2.0" (at 355.6 196.85 0)
      (effects (font (size 1.27 1.27) (thickness 0.15)) (justify left bottom) hide)
    )
    (property "Author" "Antmicro" (at 358.14 196.85 0)
      (effects (font (size 1.27 1.27) (thickness 0.15)) (justify left bottom) hide)
    )
    (property "Voltage" "" (at 360.68 196.85 0)
      (effects (font (size 1.27 1.27)) (justify left bottom) hide)
    )
    (property "Dielectric" "template_dielectric" (at 363.22 196.85 0)
      (effects (font (size 1.27 1.27)) (justify left bottom) hide)
    )
    (property "Public" "False" (at 365.76 196.85 0)
      (effects (font (size 1.27 1.27)) (justify left bottom) hide)
    )
    (pin "1")
    (pin "2")
    (instances
      (project "antmicro-hdmi-mipi-bridge-hw"
        (path ""
          (reference "C41") (unit 1)
        )
      )
    )
  )

  (symbol (lib_id "antmicroResistors0603:R_0R_0603") (at 232.41 181.61 0) (unit 1)
    (in_bom yes) (on_board yes) (dnp no)
    (property "Reference" "R20" (at 234.95 177.165 0)
      (effects (font (size 1.524 1.524)))
    )
    (property "Value" "R_0R_0603" (at 252.73 194.31 0)
      (effects (font (size 1.27 1.27) (thickness 0.15)) (justify left bottom) hide)
    )
    (property "Footprint" "antmicro-footprints:R_0603_1608Metric" (at 252.73 196.85 0)
      (effects (font (size 1.27 1.27) (thickness 0.15)) (justify left bottom) hide)
    )
    (property "Datasheet" "https://www.bourns.com/docs/product-datasheets/cr.pdf?sfvrsn=574d41f6_14" (at 252.73 199.39 0)
      (effects (font (size 1.27 1.27) (thickness 0.15)) (justify left bottom) hide)
    )
    (property "Manufacturer" "Bourns" (at 252.73 204.47 0)
      (effects (font (size 1.27 1.27) (thickness 0.15)) (justify left bottom) hide)
    )
    (property "MPN" "CR0603-J/-000ELF" (at 252.73 201.93 0)
      (effects (font (size 1.27 1.27) (thickness 0.15)) (justify left bottom) hide)
    )
    (property "Val" "0R" (at 233.68 179.705 0)
      (effects (font (size 1.27 1.27) (thickness 0.15)) (justify left bottom))
    )
    (property "License" "Apache-2.0" (at 252.73 207.01 0)
      (effects (font (size 1.27 1.27) (thickness 0.15)) (justify left bottom) hide)
    )
    (property "Author" "Antmicro" (at 252.73 209.55 0)
      (effects (font (size 1.27 1.27) (thickness 0.15)) (justify left bottom) hide)
    )
    (property "Tolerance" "~" (at 252.73 191.77 0)
      (effects (font (size 1.27 1.27)) (justify left bottom) hide)
    )
    (property "Current" "1A" (at 252.73 212.09 0)
      (effects (font (size 1.27 1.27) (thickness 0.15)) (justify left bottom) hide)
    )
    (property "Public" "False" (at 252.73 212.09 0)
      (effects (font (size 1.27 1.27)) (justify left bottom) hide)
    )
    (pin "1")
    (pin "2")
    (instances
      (project "antmicro-hdmi-mipi-bridge-hw"
        (path ""
          (reference "R20") (unit 1)
        )
      )
    )
  )

  (symbol (lib_id "antmicroResistors0402:R_10k_0402") (at 372.11 93.98 90) (unit 1)
    (in_bom yes) (on_board yes) (dnp no)
    (property "Reference" "R25" (at 374.015 89.535 90)
      (effects (font (size 1.524 1.524)) (justify right))
    )
    (property "Value" "R_10k_0402" (at 384.81 73.66 0)
      (effects (font (size 1.27 1.27) (thickness 0.15)) (justify left bottom) hide)
    )
    (property "Footprint" "antmicro-footprints:R_0402_1005Metric" (at 387.35 73.66 0)
      (effects (font (size 1.27 1.27) (thickness 0.15)) (justify left bottom) hide)
    )
    (property "Datasheet" "https://www.bourns.com/docs/product-datasheets/cr.pdf" (at 389.89 73.66 0)
      (effects (font (size 1.27 1.27) (thickness 0.15)) (justify left bottom) hide)
    )
    (property "Manufacturer" "Bourns" (at 394.97 73.66 0)
      (effects (font (size 1.27 1.27) (thickness 0.15)) (justify left bottom) hide)
    )
    (property "MPN" "CR0402-FX-1002GLF" (at 392.43 73.66 0)
      (effects (font (size 1.27 1.27) (thickness 0.15)) (justify left bottom) hide)
    )
    (property "Val" "10k" (at 377.825 90.805 90)
      (effects (font (size 1.27 1.27) (thickness 0.15)) (justify left bottom))
    )
    (property "License" "Apache-2.0" (at 397.51 73.66 0)
      (effects (font (size 1.27 1.27) (thickness 0.15)) (justify left bottom) hide)
    )
    (property "Author" "Antmicro" (at 400.05 73.66 0)
      (effects (font (size 1.27 1.27) (thickness 0.15)) (justify left bottom) hide)
    )
    (property "Tolerance" "1%" (at 382.27 73.66 0)
      (effects (font (size 1.27 1.27)) (justify left bottom) hide)
    )
    (property "Public" "False" (at 402.59 73.66 0)
      (effects (font (size 1.27 1.27)) (justify left bottom) hide)
    )
    (pin "1")
    (pin "2")
    (instances
      (project "antmicro-hdmi-mipi-bridge-hw"
        (path ""
          (reference "R25") (unit 1)
        )
      )
    )
  )

  (symbol (lib_id "antmicroInterfaceControllers:TC358743XBG") (at 73.66 156.21 0) (unit 1)
    (in_bom yes) (on_board yes) (dnp no)
    (property "Reference" "U4" (at 88.9 149.225 0)
      (effects (font (size 1.27 1.27)))
    )
    (property "Value" "TC358743XBG" (at 114.3 148.59 0)
      (effects (font (size 1.27 1.27) (thickness 0.15)) (justify left bottom) hide)
    )
    (property "Footprint" "antmicro-footprints:BGA-64_8x8_6.0x6.0mm" (at 114.3 151.13 0)
      (effects (font (size 1.27 1.27) (thickness 0.15)) (justify left bottom) hide)
    )
    (property "Datasheet" "https://toshiba.semicon-storage.com/info/TC358743XBG_datasheet_en_20171026.pdf?did=35655&prodName=TC358743XBG" (at 114.3 153.67 0)
      (effects (font (size 1.27 1.27) (thickness 0.15)) (justify left bottom) hide)
    )
    (property "MPN" "TC358743XBG" (at 82.55 152.4 0)
      (effects (font (size 1.27 1.27) (thickness 0.15)) (justify left bottom))
    )
    (property "Manufacturer" "Toshiba" (at 114.3 158.75 0)
      (effects (font (size 1.27 1.27) (thickness 0.15)) (justify left bottom) hide)
    )
    (property "Author" "Antmicro" (at 114.3 161.29 0)
      (effects (font (size 1.27 1.27) (thickness 0.15)) (justify left bottom) hide)
    )
    (property "License" "Apache-2.0" (at 114.3 163.83 0)
      (effects (font (size 1.27 1.27) (thickness 0.15)) (justify left bottom) hide)
    )
    (pin "A7")
    (pin "A8")
    (pin "B4")
    (pin "B7")
    (pin "B8")
    (pin "C1")
    (pin "C2")
    (pin "C7")
    (pin "C8")
    (pin "D1")
    (pin "D2")
    (pin "D7")
    (pin "D8")
    (pin "E1")
    (pin "E2")
    (pin "E7")
    (pin "E8")
    (pin "F1")
    (pin "F2")
    (pin "G1")
    (pin "G3")
    (pin "G4")
    (pin "G6")
    (pin "H1")
    (pin "H2")
    (pin "H3")
    (pin "H4")
    (pin "H6")
    (pin "A1")
    (pin "A2")
    (pin "A3")
    (pin "B1")
    (pin "B2")
    (pin "B3")
    (pin "B5")
    (pin "C3")
    (pin "C4")
    (pin "C5")
    (pin "C6")
    (pin "D3")
    (pin "D4")
    (pin "D5")
    (pin "D6")
    (pin "E3")
    (pin "E4")
    (pin "E5")
    (pin "E6")
    (pin "F3")
    (pin "F4")
    (pin "F5")
    (pin "F6")
    (pin "G2")
    (pin "G5")
    (pin "H5")
    (pin "H7")
    (pin "H8")
    (pin "A4")
    (pin "A5")
    (pin "A6")
    (pin "B6")
    (pin "F7")
    (pin "F8")
    (pin "G7")
    (pin "G8")
    (instances
      (project "antmicro-hdmi-mipi-bridge-hw"
        (path ""
          (reference "U4") (unit 1)
        )
      )
    )
  )

  (symbol (lib_id "antmicroFerriteBeadsandChips:FB_1kZ_0.8A_WE-CBF_0805") (at 248.285 260.35 0) (unit 1)
    (in_bom yes) (on_board yes) (dnp no)
    (property "Reference" "FB11" (at 250.825 255.27 0)
      (effects (font (size 1.524 1.524)))
    )
    (property "Value" "FB_1kZ_0.8A_WE-CBF_0805" (at 263.525 268.478 0)
      (effects (font (size 1.27 1.27) (thickness 0.15)) (justify left bottom) hide)
    )
    (property "Footprint" "antmicro-footprints:FB_0805_2012Metric" (at 263.525 271.018 0)
      (effects (font (size 1.27 1.27) (thickness 0.15)) (justify left bottom) hide)
    )
    (property "Datasheet" "https://www.we-online.com/components/products/datasheet/742792096.pdf" (at 263.525 273.558 0)
      (effects (font (size 1.27 1.27) (thickness 0.15)) (justify left bottom) hide)
    )
    (property "MPN" "742792096" (at 263.525 262.89 0)
      (effects (font (size 1.27 1.27) (thickness 0.15)) (justify left bottom) hide)
    )
    (property "Manufacturer" "Würth Elektronik" (at 263.525 276.098 0)
      (effects (font (size 1.27 1.27) (thickness 0.15)) (justify left bottom) hide)
    )
    (property "Author" "Antmicro" (at 263.525 278.638 0)
      (effects (font (size 1.27 1.27) (thickness 0.15)) (justify left bottom) hide)
    )
    (property "License" "Apache-2.0" (at 263.525 281.178 0)
      (effects (font (size 1.27 1.27) (thickness 0.15)) (justify left bottom) hide)
    )
    (property "Val" "1kZ/0.8A" (at 246.38 258.445 0)
      (effects (font (size 1.27 1.27)) (justify left bottom))
    )
    (property "Current" "" (at 268.605 283.21 0)
      (effects (font (size 1.27 1.27) (thickness 0.15)) (justify left bottom) hide)
    )
    (property "Public" "False" (at 268.605 275.59 0)
      (effects (font (size 1.27 1.27)) (justify left bottom) hide)
    )
    (pin "1")
    (pin "2")
    (instances
      (project "antmicro-hdmi-mipi-bridge-hw"
        (path ""
          (reference "FB11") (unit 1)
        )
      )
    )
  )

  (symbol (lib_id "antmicropower:GND") (at 223.52 176.53 0) (unit 1)
    (in_bom yes) (on_board yes) (dnp no)
    (property "Reference" "#PWR0189" (at 223.52 182.88 0)
      (effects (font (size 1.27 1.27)) hide)
    )
    (property "Value" "GND" (at 225.425 179.07 0)
      (effects (font (size 1.27 1.27) (thickness 0.15)) (justify left bottom))
    )
    (property "Footprint" "" (at 223.52 176.53 0)
      (effects (font (size 1.27 1.27) (thickness 0.15)) (justify left bottom) hide)
    )
    (property "Datasheet" "" (at 223.52 176.53 0)
      (effects (font (size 1.27 1.27) (thickness 0.15)) (justify left bottom) hide)
    )
    (property "Author" "Antmicro" (at 232.41 184.15 0)
      (effects (font (size 1.27 1.27) (thickness 0.15)) (justify left bottom) hide)
    )
    (property "License" "Apache-2.0" (at 232.41 186.69 0)
      (effects (font (size 1.27 1.27) (thickness 0.15)) (justify left bottom) hide)
    )
    (pin "1")
    (instances
      (project "antmicro-hdmi-mipi-bridge-hw"
        (path ""
          (reference "#PWR0189") (unit 1)
        )
      )
    )
  )

  (symbol (lib_id "antmicropower:+3V3") (at 294.64 38.1 0) (unit 1)
    (in_bom yes) (on_board yes) (dnp no)
    (property "Reference" "#PWR0173" (at 294.64 41.91 0)
      (effects (font (size 1.27 1.27)) hide)
    )
    (property "Value" "+3V3" (at 291.465 34.925 0)
      (effects (font (size 1.27 1.27) (thickness 0.15)) (justify left bottom))
    )
    (property "Footprint" "" (at 294.64 38.1 0)
      (effects (font (size 1.27 1.27) (thickness 0.15)) (justify left bottom) hide)
    )
    (property "Datasheet" "" (at 294.64 38.1 0)
      (effects (font (size 1.27 1.27) (thickness 0.15)) (justify left bottom) hide)
    )
    (property "Author" "Antmicro" (at 309.88 40.64 0)
      (effects (font (size 1.27 1.27) (thickness 0.15)) (justify left bottom) hide)
    )
    (property "License" "Apache-2.0" (at 309.88 43.18 0)
      (effects (font (size 1.27 1.27) (thickness 0.15)) (justify left bottom) hide)
    )
    (pin "1")
    (instances
      (project "antmicro-hdmi-mipi-bridge-hw"
        (path ""
          (reference "#PWR0173") (unit 1)
        )
      )
    )
  )

  (symbol (lib_id "antmicroResistors0603:R_0R_0603") (at 232.41 166.37 0) (unit 1)
    (in_bom yes) (on_board yes) (dnp no)
    (property "Reference" "R19" (at 234.95 161.925 0)
      (effects (font (size 1.524 1.524)))
    )
    (property "Value" "R_0R_0603" (at 252.73 179.07 0)
      (effects (font (size 1.27 1.27) (thickness 0.15)) (justify left bottom) hide)
    )
    (property "Footprint" "antmicro-footprints:R_0603_1608Metric" (at 252.73 181.61 0)
      (effects (font (size 1.27 1.27) (thickness 0.15)) (justify left bottom) hide)
    )
    (property "Datasheet" "https://www.bourns.com/docs/product-datasheets/cr.pdf?sfvrsn=574d41f6_14" (at 252.73 184.15 0)
      (effects (font (size 1.27 1.27) (thickness 0.15)) (justify left bottom) hide)
    )
    (property "Manufacturer" "Bourns" (at 252.73 189.23 0)
      (effects (font (size 1.27 1.27) (thickness 0.15)) (justify left bottom) hide)
    )
    (property "MPN" "CR0603-J/-000ELF" (at 252.73 186.69 0)
      (effects (font (size 1.27 1.27) (thickness 0.15)) (justify left bottom) hide)
    )
    (property "Val" "0R" (at 233.68 164.465 0)
      (effects (font (size 1.27 1.27) (thickness 0.15)) (justify left bottom))
    )
    (property "License" "Apache-2.0" (at 252.73 191.77 0)
      (effects (font (size 1.27 1.27) (thickness 0.15)) (justify left bottom) hide)
    )
    (property "Author" "Antmicro" (at 252.73 194.31 0)
      (effects (font (size 1.27 1.27) (thickness 0.15)) (justify left bottom) hide)
    )
    (property "Tolerance" "~" (at 252.73 176.53 0)
      (effects (font (size 1.27 1.27)) (justify left bottom) hide)
    )
    (property "Current" "1A" (at 252.73 196.85 0)
      (effects (font (size 1.27 1.27) (thickness 0.15)) (justify left bottom) hide)
    )
    (property "Public" "False" (at 252.73 196.85 0)
      (effects (font (size 1.27 1.27)) (justify left bottom) hide)
    )
    (pin "1")
    (pin "2")
    (instances
      (project "antmicro-hdmi-mipi-bridge-hw"
        (path ""
          (reference "R19") (unit 1)
        )
      )
    )
  )

  (symbol (lib_id "antmicropower:GND") (at 305.435 95.25 0) (mirror y) (unit 1)
    (in_bom yes) (on_board yes) (dnp no)
    (property "Reference" "#PWR0164" (at 305.435 101.6 0)
      (effects (font (size 1.27 1.27)) hide)
    )
    (property "Value" "GND" (at 309.245 96.52 0)
      (effects (font (size 1.27 1.27) (thickness 0.15)) (justify left bottom))
    )
    (property "Footprint" "" (at 305.435 95.25 0)
      (effects (font (size 1.27 1.27) (thickness 0.15)) (justify left bottom) hide)
    )
    (property "Datasheet" "" (at 305.435 95.25 0)
      (effects (font (size 1.27 1.27) (thickness 0.15)) (justify left bottom) hide)
    )
    (property "Author" "Antmicro" (at 296.545 102.87 0)
      (effects (font (size 1.27 1.27) (thickness 0.15)) (justify left bottom) hide)
    )
    (property "License" "Apache-2.0" (at 296.545 105.41 0)
      (effects (font (size 1.27 1.27) (thickness 0.15)) (justify left bottom) hide)
    )
    (pin "1")
    (instances
      (project "antmicro-hdmi-mipi-bridge-hw"
        (path ""
          (reference "#PWR0164") (unit 1)
        )
      )
    )
  )

  (symbol (lib_id "antmicropower:GND") (at 92.71 260.35 0) (unit 1)
    (in_bom yes) (on_board yes) (dnp no)
    (property "Reference" "#PWR0152" (at 92.71 266.7 0)
      (effects (font (size 1.27 1.27)) hide)
    )
    (property "Value" "GND" (at 90.805 265.43 0)
      (effects (font (size 1.27 1.27) (thickness 0.15)) (justify left bottom))
    )
    (property "Footprint" "" (at 92.71 260.35 0)
      (effects (font (size 1.27 1.27) (thickness 0.15)) (justify left bottom) hide)
    )
    (property "Datasheet" "" (at 92.71 260.35 0)
      (effects (font (size 1.27 1.27) (thickness 0.15)) (justify left bottom) hide)
    )
    (property "Author" "Antmicro" (at 101.6 267.97 0)
      (effects (font (size 1.27 1.27) (thickness 0.15)) (justify left bottom) hide)
    )
    (property "License" "Apache-2.0" (at 101.6 270.51 0)
      (effects (font (size 1.27 1.27) (thickness 0.15)) (justify left bottom) hide)
    )
    (pin "1")
    (instances
      (project "antmicro-hdmi-mipi-bridge-hw"
        (path ""
          (reference "#PWR0152") (unit 1)
        )
      )
    )
  )

  (symbol (lib_id "antmicroCapacitors0402:C_470p_0402") (at 223.52 262.89 270) (unit 1)
    (in_bom yes) (on_board yes) (dnp no)
    (property "Reference" "C50" (at 220.98 264.16 90)
      (effects (font (size 1.524 1.524)) (justify right))
    )
    (property "Value" "C_470p_0402" (at 213.36 283.21 0)
      (effects (font (size 1.27 1.27) (thickness 0.15)) (justify left bottom) hide)
    )
    (property "Footprint" "antmicro-footprints:C_0402_1005Metric" (at 210.82 283.21 0)
      (effects (font (size 1.27 1.27) (thickness 0.15)) (justify left bottom) hide)
    )
    (property "Datasheet" "https://www.passivecomponent.com/wp-content/uploads/datasheet/WTC_MLCC_General_Purpose.pdf" (at 208.28 283.21 0)
      (effects (font (size 1.27 1.27) (thickness 0.15)) (justify left bottom) hide)
    )
    (property "Manufacturer" "Walsin" (at 203.2 283.21 0)
      (effects (font (size 1.27 1.27) (thickness 0.15)) (justify left bottom) hide)
    )
    (property "MPN" "0402B471K250CT" (at 205.74 283.21 0)
      (effects (font (size 1.27 1.27) (thickness 0.15)) (justify left bottom) hide)
    )
    (property "Val" "470p" (at 216.535 267.335 90)
      (effects (font (size 1.27 1.27) (thickness 0.15)) (justify left bottom))
    )
    (property "License" "Apache-2.0" (at 200.66 283.21 0)
      (effects (font (size 1.27 1.27) (thickness 0.15)) (justify left bottom) hide)
    )
    (property "Author" "Antmicro" (at 198.12 283.21 0)
      (effects (font (size 1.27 1.27) (thickness 0.15)) (justify left bottom) hide)
    )
    (property "Voltage" "" (at 195.58 283.21 0)
      (effects (font (size 1.27 1.27)) (justify left bottom) hide)
    )
    (property "Dielectric" "" (at 193.04 283.21 0)
      (effects (font (size 1.27 1.27)) (justify left bottom) hide)
    )
    (property "Public" "False" (at 190.5 283.21 0)
      (effects (font (size 1.27 1.27)) (justify left bottom) hide)
    )
    (pin "1")
    (pin "2")
    (instances
      (project "antmicro-hdmi-mipi-bridge-hw"
        (path ""
          (reference "C50") (unit 1)
        )
      )
    )
  )

  (symbol (lib_id "antmicropower:GND") (at 335.28 108.585 0) (mirror y) (unit 1)
    (in_bom yes) (on_board yes) (dnp no)
    (property "Reference" "#PWR0169" (at 335.28 114.935 0)
      (effects (font (size 1.27 1.27)) hide)
    )
    (property "Value" "GND" (at 337.185 113.665 0)
      (effects (font (size 1.27 1.27) (thickness 0.15)) (justify left bottom))
    )
    (property "Footprint" "" (at 335.28 108.585 0)
      (effects (font (size 1.27 1.27) (thickness 0.15)) (justify left bottom) hide)
    )
    (property "Datasheet" "" (at 335.28 108.585 0)
      (effects (font (size 1.27 1.27) (thickness 0.15)) (justify left bottom) hide)
    )
    (property "Author" "Antmicro" (at 326.39 116.205 0)
      (effects (font (size 1.27 1.27) (thickness 0.15)) (justify left bottom) hide)
    )
    (property "License" "Apache-2.0" (at 326.39 118.745 0)
      (effects (font (size 1.27 1.27) (thickness 0.15)) (justify left bottom) hide)
    )
    (pin "1")
    (instances
      (project "antmicro-hdmi-mipi-bridge-hw"
        (path ""
          (reference "#PWR0169") (unit 1)
        )
      )
    )
  )

  (symbol (lib_id "antmicroCapacitors0402:C_100n_0402") (at 186.69 250.19 90) (unit 1)
    (in_bom yes) (on_board yes) (dnp no)
    (property "Reference" "C31" (at 179.705 247.015 90)
      (effects (font (size 1.524 1.524)) (justify right))
    )
    (property "Value" "C_100n_0402" (at 196.85 229.87 0)
      (effects (font (size 1.27 1.27) (thickness 0.15)) (justify left bottom) hide)
    )
    (property "Footprint" "antmicro-footprints:C_0402_1005Metric" (at 199.39 229.87 0)
      (effects (font (size 1.27 1.27) (thickness 0.15)) (justify left bottom) hide)
    )
    (property "Datasheet" "https://www.murata.com/products/productdetail?partno=GRM155R61H104KE14%23" (at 201.93 229.87 0)
      (effects (font (size 1.27 1.27) (thickness 0.15)) (justify left bottom) hide)
    )
    (property "Manufacturer" "Murata" (at 207.01 229.87 0)
      (effects (font (size 1.27 1.27) (thickness 0.15)) (justify left bottom) hide)
    )
    (property "MPN" "GRM155R61H104KE14D" (at 204.47 229.87 0)
      (effects (font (size 1.27 1.27) (thickness 0.15)) (justify left bottom) hide)
    )
    (property "Val" "100n" (at 184.785 248.285 90)
      (effects (font (size 1.27 1.27) (thickness 0.15)) (justify left bottom))
    )
    (property "License" "Apache-2.0" (at 209.55 229.87 0)
      (effects (font (size 1.27 1.27) (thickness 0.15)) (justify left bottom) hide)
    )
    (property "Author" "Antmicro" (at 212.09 229.87 0)
      (effects (font (size 1.27 1.27) (thickness 0.15)) (justify left bottom) hide)
    )
    (property "Voltage" "50V" (at 214.63 229.87 0)
      (effects (font (size 1.27 1.27)) (justify left bottom) hide)
    )
    (property "Dielectric" "X5R" (at 217.17 229.87 0)
      (effects (font (size 1.27 1.27)) (justify left bottom) hide)
    )
    (property "Public" "False" (at 219.71 229.87 0)
      (effects (font (size 1.27 1.27)) (justify left bottom) hide)
    )
    (pin "1")
    (pin "2")
    (instances
      (project "antmicro-hdmi-mipi-bridge-hw"
        (path ""
          (reference "C31") (unit 1)
        )
      )
    )
  )

  (symbol (lib_id "antmicroCapacitors0603:C_4u7_0603") (at 234.95 219.71 90) (unit 1)
    (in_bom yes) (on_board yes) (dnp no) (fields_autoplaced)
    (property "Reference" "C51" (at 237.49 215.8936 90)
      (effects (font (size 1.524 1.524)) (justify right))
    )
    (property "Value" "C_4u7_0603" (at 245.11 199.39 0)
      (effects (font (size 1.27 1.27) (thickness 0.15)) (justify left bottom) hide)
    )
    (property "Footprint" "antmicro-footprints:C_0603_1608Metric" (at 247.65 199.39 0)
      (effects (font (size 1.27 1.27) (thickness 0.15)) (justify left bottom) hide)
    )
    (property "Datasheet" "https://product.tdk.com/en/search/capacitor/ceramic/mlcc/info?part_no=C1608X5R1V475M080AC" (at 250.19 199.39 0)
      (effects (font (size 1.27 1.27) (thickness 0.15)) (justify left bottom) hide)
    )
    (property "Manufacturer" "TDK" (at 255.27 199.39 0)
      (effects (font (size 1.27 1.27) (thickness 0.15)) (justify left bottom) hide)
    )
    (property "MPN" "C1608X5R1V475M080AC" (at 252.73 199.39 0)
      (effects (font (size 1.27 1.27) (thickness 0.15)) (justify left bottom) hide)
    )
    (property "Val" "4u7" (at 237.49 218.4336 90)
      (effects (font (size 1.27 1.27) (thickness 0.15)) (justify right))
    )
    (property "License" "Apache-2.0" (at 257.81 199.39 0)
      (effects (font (size 1.27 1.27) (thickness 0.15)) (justify left bottom) hide)
    )
    (property "Author" "Antmicro" (at 260.35 199.39 0)
      (effects (font (size 1.27 1.27) (thickness 0.15)) (justify left bottom) hide)
    )
    (property "Voltage" "" (at 262.89 199.39 0)
      (effects (font (size 1.27 1.27)) (justify left bottom) hide)
    )
    (property "Dielectric" "" (at 265.43 199.39 0)
      (effects (font (size 1.27 1.27)) (justify left bottom) hide)
    )
    (property "Public" "False" (at 267.97 199.39 0)
      (effects (font (size 1.27 1.27)) (justify left bottom) hide)
    )
    (pin "1")
    (pin "2")
    (instances
      (project "antmicro-hdmi-mipi-bridge-hw"
        (path ""
          (reference "C51") (unit 1)
        )
      )
    )
  )

  (symbol (lib_id "antmicroResistors0402:R_22R_0402") (at 373.38 39.37 0) (unit 1)
    (in_bom yes) (on_board yes) (dnp no)
    (property "Reference" "R26" (at 375.92 34.925 0)
      (effects (font (size 1.524 1.524)))
    )
    (property "Value" "R_22R_0402" (at 393.7 52.07 0)
      (effects (font (size 1.27 1.27) (thickness 0.15)) (justify left bottom) hide)
    )
    (property "Footprint" "antmicro-footprints:R_0402_1005Metric" (at 393.7 54.61 0)
      (effects (font (size 1.27 1.27) (thickness 0.15)) (justify left bottom) hide)
    )
    (property "Datasheet" "https://www.bourns.com/docs/product-datasheets/cr.pdf" (at 393.7 57.15 0)
      (effects (font (size 1.27 1.27) (thickness 0.15)) (justify left bottom) hide)
    )
    (property "Manufacturer" "Bourns" (at 393.7 62.23 0)
      (effects (font (size 1.27 1.27) (thickness 0.15)) (justify left bottom) hide)
    )
    (property "MPN" "CR0402-FX-22R0GLF" (at 393.7 59.69 0)
      (effects (font (size 1.27 1.27) (thickness 0.15)) (justify left bottom) hide)
    )
    (property "Val" "22R" (at 374.015 38.1 0)
      (effects (font (size 1.27 1.27) (thickness 0.15)) (justify left bottom))
    )
    (property "License" "Apache-2.0" (at 393.7 64.77 0)
      (effects (font (size 1.27 1.27) (thickness 0.15)) (justify left bottom) hide)
    )
    (property "Author" "Antmicro" (at 393.7 67.31 0)
      (effects (font (size 1.27 1.27) (thickness 0.15)) (justify left bottom) hide)
    )
    (property "Tolerance" "1%" (at 393.7 49.53 0)
      (effects (font (size 1.27 1.27)) (justify left bottom) hide)
    )
    (property "Public" "False" (at 393.7 69.85 0)
      (effects (font (size 1.27 1.27)) (justify left bottom) hide)
    )
    (pin "1")
    (pin "2")
    (instances
      (project "antmicro-hdmi-mipi-bridge-hw"
        (path ""
          (reference "R26") (unit 1)
        )
      )
    )
  )

  (symbol (lib_id "antmicroResistors0402:R_10k_0402") (at 330.2 93.98 270) (mirror x) (unit 1)
    (in_bom yes) (on_board yes) (dnp no)
    (property "Reference" "R23" (at 328.295 90.17 90)
      (effects (font (size 1.524 1.524)) (justify right))
    )
    (property "Value" "R_10k_0402" (at 317.5 73.66 0)
      (effects (font (size 1.27 1.27) (thickness 0.15)) (justify left bottom) hide)
    )
    (property "Footprint" "antmicro-footprints:R_0402_1005Metric" (at 314.96 73.66 0)
      (effects (font (size 1.27 1.27) (thickness 0.15)) (justify left bottom) hide)
    )
    (property "Datasheet" "https://www.bourns.com/docs/product-datasheets/cr.pdf" (at 312.42 73.66 0)
      (effects (font (size 1.27 1.27) (thickness 0.15)) (justify left bottom) hide)
    )
    (property "Manufacturer" "Bourns" (at 307.34 73.66 0)
      (effects (font (size 1.27 1.27) (thickness 0.15)) (justify left bottom) hide)
    )
    (property "MPN" "CR0402-FX-1002GLF" (at 309.88 73.66 0)
      (effects (font (size 1.27 1.27) (thickness 0.15)) (justify left bottom) hide)
    )
    (property "Val" "10k" (at 323.85 92.075 90)
      (effects (font (size 1.27 1.27) (thickness 0.15)) (justify left bottom))
    )
    (property "License" "Apache-2.0" (at 304.8 73.66 0)
      (effects (font (size 1.27 1.27) (thickness 0.15)) (justify left bottom) hide)
    )
    (property "Author" "Antmicro" (at 302.26 73.66 0)
      (effects (font (size 1.27 1.27) (thickness 0.15)) (justify left bottom) hide)
    )
    (property "Tolerance" "1%" (at 320.04 73.66 0)
      (effects (font (size 1.27 1.27)) (justify left bottom) hide)
    )
    (property "Public" "False" (at 299.72 73.66 0)
      (effects (font (size 1.27 1.27)) (justify left bottom) hide)
    )
    (pin "1")
    (pin "2")
    (instances
      (project "antmicro-hdmi-mipi-bridge-hw"
        (path ""
          (reference "R23") (unit 1)
        )
      )
    )
  )

  (symbol (lib_id "antmicropower:GND") (at 234.95 237.49 0) (unit 1)
    (in_bom yes) (on_board yes) (dnp no)
    (property "Reference" "#PWR0185" (at 234.95 243.84 0)
      (effects (font (size 1.27 1.27)) hide)
    )
    (property "Value" "GND" (at 236.855 240.03 0)
      (effects (font (size 1.27 1.27) (thickness 0.15)) (justify left bottom))
    )
    (property "Footprint" "" (at 234.95 237.49 0)
      (effects (font (size 1.27 1.27) (thickness 0.15)) (justify left bottom) hide)
    )
    (property "Datasheet" "" (at 234.95 237.49 0)
      (effects (font (size 1.27 1.27) (thickness 0.15)) (justify left bottom) hide)
    )
    (property "Author" "Antmicro" (at 243.84 245.11 0)
      (effects (font (size 1.27 1.27) (thickness 0.15)) (justify left bottom) hide)
    )
    (property "License" "Apache-2.0" (at 243.84 247.65 0)
      (effects (font (size 1.27 1.27) (thickness 0.15)) (justify left bottom) hide)
    )
    (pin "1")
    (instances
      (project "antmicro-hdmi-mipi-bridge-hw"
        (path ""
          (reference "#PWR0185") (unit 1)
        )
      )
    )
  )

  (symbol (lib_id "antmicroCapacitors0402:C_470p_0402") (at 223.52 245.11 270) (unit 1)
    (in_bom yes) (on_board yes) (dnp no)
    (property "Reference" "C49" (at 220.98 246.38 90)
      (effects (font (size 1.524 1.524)) (justify right))
    )
    (property "Value" "C_470p_0402" (at 213.36 265.43 0)
      (effects (font (size 1.27 1.27) (thickness 0.15)) (justify left bottom) hide)
    )
    (property "Footprint" "antmicro-footprints:C_0402_1005Metric" (at 210.82 265.43 0)
      (effects (font (size 1.27 1.27) (thickness 0.15)) (justify left bottom) hide)
    )
    (property "Datasheet" "https://www.passivecomponent.com/wp-content/uploads/datasheet/WTC_MLCC_General_Purpose.pdf" (at 208.28 265.43 0)
      (effects (font (size 1.27 1.27) (thickness 0.15)) (justify left bottom) hide)
    )
    (property "Manufacturer" "Walsin" (at 203.2 265.43 0)
      (effects (font (size 1.27 1.27) (thickness 0.15)) (justify left bottom) hide)
    )
    (property "MPN" "0402B471K250CT" (at 205.74 265.43 0)
      (effects (font (size 1.27 1.27) (thickness 0.15)) (justify left bottom) hide)
    )
    (property "Val" "470p" (at 216.535 249.555 90)
      (effects (font (size 1.27 1.27) (thickness 0.15)) (justify left bottom))
    )
    (property "License" "Apache-2.0" (at 200.66 265.43 0)
      (effects (font (size 1.27 1.27) (thickness 0.15)) (justify left bottom) hide)
    )
    (property "Author" "Antmicro" (at 198.12 265.43 0)
      (effects (font (size 1.27 1.27) (thickness 0.15)) (justify left bottom) hide)
    )
    (property "Voltage" "" (at 195.58 265.43 0)
      (effects (font (size 1.27 1.27)) (justify left bottom) hide)
    )
    (property "Dielectric" "" (at 193.04 265.43 0)
      (effects (font (size 1.27 1.27)) (justify left bottom) hide)
    )
    (property "Public" "False" (at 190.5 265.43 0)
      (effects (font (size 1.27 1.27)) (justify left bottom) hide)
    )
    (pin "1")
    (pin "2")
    (instances
      (project "antmicro-hdmi-mipi-bridge-hw"
        (path ""
          (reference "C49") (unit 1)
        )
      )
    )
  )

  (symbol (lib_id "antmicroTestPoints:TP_0.75mm_SMD") (at 358.14 106.68 0) (unit 1)
    (in_bom no) (on_board yes) (dnp no)
    (property "Reference" "TP8" (at 366.395 106.68 0)
      (effects (font (size 1.27 1.27)) (justify right))
    )
    (property "Value" "TP_0.75mm_SMD" (at 373.38 114.3 0)
      (effects (font (size 1.27 1.27) (thickness 0.15)) (justify left bottom) hide)
    )
    (property "Footprint" "antmicro-footprints:TP_SMD_0.75mm" (at 373.38 116.84 0)
      (effects (font (size 1.27 1.27) (thickness 0.15)) (justify left bottom) hide)
    )
    (property "Datasheet" "" (at 373.38 119.38 0)
      (effects (font (size 1.27 1.27) (thickness 0.15)) (justify left bottom) hide)
    )
    (property "MPN" "" (at 358.14 106.68 0)
      (effects (font (size 1.27 1.27) (thickness 0.15)) (justify left bottom) hide)
    )
    (property "Manufacturer" "" (at 358.14 106.68 0)
      (effects (font (size 1.27 1.27) (thickness 0.15)) (justify left bottom) hide)
    )
    (property "Author" "Antmicro" (at 373.38 121.92 0)
      (effects (font (size 1.27 1.27) (thickness 0.15)) (justify left bottom) hide)
    )
    (property "License" "Apache-2.0" (at 373.38 124.46 0)
      (effects (font (size 1.27 1.27) (thickness 0.15)) (justify left bottom) hide)
    )
    (property "Public" "False" (at 368.3 120.65 0)
      (effects (font (size 1.27 1.27)) (justify left bottom) hide)
    )
    (pin "1")
    (instances
      (project "antmicro-hdmi-mipi-bridge-hw"
        (path ""
          (reference "TP8") (unit 1)
        )
      )
    )
  )

  (symbol (lib_id "antmicroCapacitors0402:C_47p_0402") (at 328.93 46.99 90) (unit 1)
    (in_bom yes) (on_board yes) (dnp no)
    (property "Reference" "C39" (at 335.915 43.18 90)
      (effects (font (size 1.524 1.524)) (justify left))
    )
    (property "Value" "C_47p_0402" (at 339.09 26.67 0)
      (effects (font (size 1.27 1.27) (thickness 0.15)) (justify left bottom) hide)
    )
    (property "Footprint" "antmicro-footprints:C_0402_1005Metric" (at 341.63 26.67 0)
      (effects (font (size 1.27 1.27) (thickness 0.15)) (justify left bottom) hide)
    )
    (property "Datasheet" "https://www.kemet.com/en/us/capacitors/product/C0402C470J5GACTU.html" (at 344.17 26.67 0)
      (effects (font (size 1.27 1.27) (thickness 0.15)) (justify left bottom) hide)
    )
    (property "Manufacturer" "KEMET" (at 349.25 26.67 0)
      (effects (font (size 1.27 1.27) (thickness 0.15)) (justify left bottom) hide)
    )
    (property "MPN" "C0402C470J5GACTU" (at 346.71 26.67 0)
      (effects (font (size 1.27 1.27) (thickness 0.15)) (justify left bottom) hide)
    )
    (property "Val" "47p" (at 335.28 44.45 90)
      (effects (font (size 1.27 1.27) (thickness 0.15)) (justify left bottom))
    )
    (property "License" "Apache-2.0" (at 351.79 26.67 0)
      (effects (font (size 1.27 1.27) (thickness 0.15)) (justify left bottom) hide)
    )
    (property "Author" "Antmicro" (at 354.33 26.67 0)
      (effects (font (size 1.27 1.27) (thickness 0.15)) (justify left bottom) hide)
    )
    (property "Voltage" "" (at 356.87 26.67 0)
      (effects (font (size 1.27 1.27)) (justify left bottom) hide)
    )
    (property "Dielectric" "C0G" (at 359.41 26.67 0)
      (effects (font (size 1.27 1.27)) (justify left bottom) hide)
    )
    (property "Public" "False" (at 361.95 26.67 0)
      (effects (font (size 1.27 1.27)) (justify left bottom) hide)
    )
    (pin "1")
    (pin "2")
    (instances
      (project "antmicro-hdmi-mipi-bridge-hw"
        (path ""
          (reference "C39") (unit 1)
        )
      )
    )
  )

  (symbol (lib_id "antmicropower:+3V3") (at 332.74 204.47 0) (unit 1)
    (in_bom yes) (on_board yes) (dnp no)
    (property "Reference" "#PWR0183" (at 332.74 208.28 0)
      (effects (font (size 1.27 1.27)) hide)
    )
    (property "Value" "+3V3" (at 329.565 201.295 0)
      (effects (font (size 1.27 1.27) (thickness 0.15)) (justify left bottom))
    )
    (property "Footprint" "" (at 332.74 204.47 0)
      (effects (font (size 1.27 1.27) (thickness 0.15)) (justify left bottom) hide)
    )
    (property "Datasheet" "" (at 332.74 204.47 0)
      (effects (font (size 1.27 1.27) (thickness 0.15)) (justify left bottom) hide)
    )
    (property "Author" "Antmicro" (at 347.98 207.01 0)
      (effects (font (size 1.27 1.27) (thickness 0.15)) (justify left bottom) hide)
    )
    (property "License" "Apache-2.0" (at 347.98 209.55 0)
      (effects (font (size 1.27 1.27) (thickness 0.15)) (justify left bottom) hide)
    )
    (pin "1")
    (instances
      (project "antmicro-hdmi-mipi-bridge-hw"
        (path ""
          (reference "#PWR0183") (unit 1)
        )
      )
    )
  )

  (symbol (lib_id "antmicroFerriteBeadsandChips:FB_1kZ_0.8A_WE-CBF_0805") (at 248.285 212.09 0) (unit 1)
    (in_bom yes) (on_board yes) (dnp no)
    (property "Reference" "FB8" (at 250.825 207.01 0)
      (effects (font (size 1.524 1.524)))
    )
    (property "Value" "FB_1kZ_0.8A_WE-CBF_0805" (at 263.525 220.218 0)
      (effects (font (size 1.27 1.27) (thickness 0.15)) (justify left bottom) hide)
    )
    (property "Footprint" "antmicro-footprints:FB_0805_2012Metric" (at 263.525 222.758 0)
      (effects (font (size 1.27 1.27) (thickness 0.15)) (justify left bottom) hide)
    )
    (property "Datasheet" "https://www.we-online.com/components/products/datasheet/742792096.pdf" (at 263.525 225.298 0)
      (effects (font (size 1.27 1.27) (thickness 0.15)) (justify left bottom) hide)
    )
    (property "MPN" "742792096" (at 263.525 214.63 0)
      (effects (font (size 1.27 1.27) (thickness 0.15)) (justify left bottom) hide)
    )
    (property "Manufacturer" "Würth Elektronik" (at 263.525 227.838 0)
      (effects (font (size 1.27 1.27) (thickness 0.15)) (justify left bottom) hide)
    )
    (property "Author" "Antmicro" (at 263.525 230.378 0)
      (effects (font (size 1.27 1.27) (thickness 0.15)) (justify left bottom) hide)
    )
    (property "License" "Apache-2.0" (at 263.525 232.918 0)
      (effects (font (size 1.27 1.27) (thickness 0.15)) (justify left bottom) hide)
    )
    (property "Val" "1kZ/0.8A" (at 246.38 209.55 0)
      (effects (font (size 1.27 1.27)) (justify left bottom))
    )
    (property "Current" "" (at 268.605 234.95 0)
      (effects (font (size 1.27 1.27) (thickness 0.15)) (justify left bottom) hide)
    )
    (property "Public" "False" (at 268.605 227.33 0)
      (effects (font (size 1.27 1.27)) (justify left bottom) hide)
    )
    (pin "1")
    (pin "2")
    (instances
      (project "antmicro-hdmi-mipi-bridge-hw"
        (path ""
          (reference "FB8") (unit 1)
        )
      )
    )
  )

  (symbol (lib_id "antmicroCapacitors0402:C_47p_0402") (at 367.03 46.99 90) (unit 1)
    (in_bom yes) (on_board yes) (dnp no)
    (property "Reference" "C44" (at 374.015 43.18 90)
      (effects (font (size 1.524 1.524)) (justify left))
    )
    (property "Value" "C_47p_0402" (at 377.19 26.67 0)
      (effects (font (size 1.27 1.27) (thickness 0.15)) (justify left bottom) hide)
    )
    (property "Footprint" "antmicro-footprints:C_0402_1005Metric" (at 379.73 26.67 0)
      (effects (font (size 1.27 1.27) (thickness 0.15)) (justify left bottom) hide)
    )
    (property "Datasheet" "https://www.kemet.com/en/us/capacitors/product/C0402C470J5GACTU.html" (at 382.27 26.67 0)
      (effects (font (size 1.27 1.27) (thickness 0.15)) (justify left bottom) hide)
    )
    (property "Manufacturer" "KEMET" (at 387.35 26.67 0)
      (effects (font (size 1.27 1.27) (thickness 0.15)) (justify left bottom) hide)
    )
    (property "MPN" "C0402C470J5GACTU" (at 384.81 26.67 0)
      (effects (font (size 1.27 1.27) (thickness 0.15)) (justify left bottom) hide)
    )
    (property "Val" "47p" (at 373.38 44.45 90)
      (effects (font (size 1.27 1.27) (thickness 0.15)) (justify left bottom))
    )
    (property "License" "Apache-2.0" (at 389.89 26.67 0)
      (effects (font (size 1.27 1.27) (thickness 0.15)) (justify left bottom) hide)
    )
    (property "Author" "Antmicro" (at 392.43 26.67 0)
      (effects (font (size 1.27 1.27) (thickness 0.15)) (justify left bottom) hide)
    )
    (property "Voltage" "" (at 394.97 26.67 0)
      (effects (font (size 1.27 1.27)) (justify left bottom) hide)
    )
    (property "Dielectric" "C0G" (at 397.51 26.67 0)
      (effects (font (size 1.27 1.27)) (justify left bottom) hide)
    )
    (property "Public" "False" (at 400.05 26.67 0)
      (effects (font (size 1.27 1.27)) (justify left bottom) hide)
    )
    (pin "1")
    (pin "2")
    (instances
      (project "antmicro-hdmi-mipi-bridge-hw"
        (path ""
          (reference "C44") (unit 1)
        )
      )
    )
  )

  (symbol (lib_id "antmicropower:GND") (at 223.52 207.01 0) (unit 1)
    (in_bom yes) (on_board yes) (dnp no)
    (property "Reference" "#PWR0159" (at 223.52 213.36 0)
      (effects (font (size 1.27 1.27)) hide)
    )
    (property "Value" "GND" (at 225.425 209.55 0)
      (effects (font (size 1.27 1.27) (thickness 0.15)) (justify left bottom))
    )
    (property "Footprint" "" (at 223.52 207.01 0)
      (effects (font (size 1.27 1.27) (thickness 0.15)) (justify left bottom) hide)
    )
    (property "Datasheet" "" (at 223.52 207.01 0)
      (effects (font (size 1.27 1.27) (thickness 0.15)) (justify left bottom) hide)
    )
    (property "Author" "Antmicro" (at 232.41 214.63 0)
      (effects (font (size 1.27 1.27) (thickness 0.15)) (justify left bottom) hide)
    )
    (property "License" "Apache-2.0" (at 232.41 217.17 0)
      (effects (font (size 1.27 1.27) (thickness 0.15)) (justify left bottom) hide)
    )
    (pin "1")
    (instances
      (project "antmicro-hdmi-mipi-bridge-hw"
        (path ""
          (reference "#PWR0159") (unit 1)
        )
      )
    )
  )

  (symbol (lib_id "antmicroPMICVoltageRegulatorsLinear:TLV73312PDBVT") (at 334.01 207.01 0) (unit 1)
    (in_bom yes) (on_board yes) (dnp no)
    (property "Reference" "IC4" (at 344.17 201.295 0)
      (effects (font (size 1.27 1.27)))
    )
    (property "Value" "TLV73312PDBVT" (at 336.55 203.835 0)
      (effects (font (size 1.27 1.27) (thickness 0.15)) (justify left bottom) hide)
    )
    (property "Footprint" "antmicro-footprints:SOT-23-5" (at 369.57 214.63 0)
      (effects (font (size 1.27 1.27) (thickness 0.15)) (justify left bottom) hide)
    )
    (property "Datasheet" "https://www.ti.com/lit/ds/symlink/tlv733p.pdf?HQS=dis-mous-null-mousermode-dsf-pf-null-wwe&ts=1676978230940&ref_url=https%253A%252F%252Fwww.mouser.com%252F" (at 369.57 217.17 0)
      (effects (font (size 1.27 1.27) (thickness 0.15)) (justify left bottom) hide)
    )
    (property "MPN" "TLV73312PDBVT" (at 336.55 203.835 0)
      (effects (font (size 1.27 1.27) (thickness 0.15)) (justify left bottom))
    )
    (property "Manufacturer" "Texas Instruments" (at 369.57 222.25 0)
      (effects (font (size 1.27 1.27) (thickness 0.15)) (justify left bottom) hide)
    )
    (property "Author" "Antmicro" (at 369.57 224.79 0)
      (effects (font (size 1.27 1.27) (thickness 0.15)) (justify left bottom) hide)
    )
    (property "License" "Apache-2.0" (at 369.57 227.33 0)
      (effects (font (size 1.27 1.27) (thickness 0.15)) (justify left bottom) hide)
    )
    (pin "1")
    (pin "2")
    (pin "3")
    (pin "4")
    (pin "5")
    (instances
      (project "antmicro-hdmi-mipi-bridge-hw"
        (path ""
          (reference "IC4") (unit 1)
        )
      )
    )
  )

  (symbol (lib_id "antmicroCapacitors0402:C_100n_0402") (at 294.64 46.99 90) (unit 1)
    (in_bom yes) (on_board yes) (dnp no)
    (property "Reference" "C35" (at 292.735 43.18 90)
      (effects (font (size 1.524 1.524)) (justify left))
    )
    (property "Value" "C_100n_0402" (at 304.8 26.67 0)
      (effects (font (size 1.27 1.27) (thickness 0.15)) (justify left bottom) hide)
    )
    (property "Footprint" "antmicro-footprints:C_0402_1005Metric" (at 307.34 26.67 0)
      (effects (font (size 1.27 1.27) (thickness 0.15)) (justify left bottom) hide)
    )
    (property "Datasheet" "https://www.murata.com/products/productdetail?partno=GRM155R61H104KE14%23" (at 309.88 26.67 0)
      (effects (font (size 1.27 1.27) (thickness 0.15)) (justify left bottom) hide)
    )
    (property "Manufacturer" "Murata" (at 314.96 26.67 0)
      (effects (font (size 1.27 1.27) (thickness 0.15)) (justify left bottom) hide)
    )
    (property "MPN" "GRM155R61H104KE14D" (at 312.42 26.67 0)
      (effects (font (size 1.27 1.27) (thickness 0.15)) (justify left bottom) hide)
    )
    (property "Val" "100n" (at 292.1 45.085 90)
      (effects (font (size 1.27 1.27) (thickness 0.15)) (justify left bottom))
    )
    (property "License" "Apache-2.0" (at 317.5 26.67 0)
      (effects (font (size 1.27 1.27) (thickness 0.15)) (justify left bottom) hide)
    )
    (property "Author" "Antmicro" (at 320.04 26.67 0)
      (effects (font (size 1.27 1.27) (thickness 0.15)) (justify left bottom) hide)
    )
    (property "Voltage" "50V" (at 322.58 26.67 0)
      (effects (font (size 1.27 1.27)) (justify left bottom) hide)
    )
    (property "Dielectric" "X5R" (at 325.12 26.67 0)
      (effects (font (size 1.27 1.27)) (justify left bottom) hide)
    )
    (property "Public" "False" (at 327.66 26.67 0)
      (effects (font (size 1.27 1.27)) (justify left bottom) hide)
    )
    (pin "1")
    (pin "2")
    (instances
      (project "antmicro-hdmi-mipi-bridge-hw"
        (path ""
          (reference "C35") (unit 1)
        )
      )
    )
  )

  (symbol (lib_id "antmicroLogicTranslatorsLevelShifters:PCA9517ATP") (at 337.82 99.06 0) (unit 1)
    (in_bom yes) (on_board yes) (dnp no)
    (property "Reference" "U6" (at 347.345 92.71 0)
      (effects (font (size 1.524 1.524)))
    )
    (property "Value" "PCA9517ATP" (at 340.995 95.885 0)
      (effects (font (size 1.27 1.27) (thickness 0.15)) (justify left bottom))
    )
    (property "Footprint" "antmicro-footprints:SOT1069-2" (at 370.84 106.68 0)
      (effects (font (size 1.27 1.27) (thickness 0.15)) (justify left bottom) hide)
    )
    (property "Datasheet" "https://www.nxp.com/docs/en/data-sheet/PCA9517A.pdf" (at 370.84 109.22 0)
      (effects (font (size 1.27 1.27) (thickness 0.15)) (justify left bottom) hide)
    )
    (property "MPN" "PCA9517ATP" (at 370.84 111.76 0)
      (effects (font (size 1.27 1.27) (thickness 0.15)) (justify left bottom) hide)
    )
    (property "Manufacturer" "NXP" (at 370.84 114.3 0)
      (effects (font (size 1.27 1.27) (thickness 0.15)) (justify left bottom) hide)
    )
    (property "Author" "Antmicro" (at 370.84 116.84 0)
      (effects (font (size 1.27 1.27) (thickness 0.15)) (justify left bottom) hide)
    )
    (property "License" "Apache-2.0" (at 370.84 119.38 0)
      (effects (font (size 1.27 1.27) (thickness 0.15)) (justify left bottom) hide)
    )
    (pin "1")
    (pin "2")
    (pin "3")
    (pin "4")
    (pin "5")
    (pin "6")
    (pin "7")
    (pin "8")
    (pin "9")
    (instances
      (project "antmicro-hdmi-mipi-bridge-hw"
        (path ""
          (reference "U6") (unit 1)
        )
      )
    )
  )

  (symbol (lib_id "antmicropower:GND") (at 355.6 177.8 0) (unit 1)
    (in_bom yes) (on_board yes) (dnp no)
    (property "Reference" "#PWR0180" (at 355.6 184.15 0)
      (effects (font (size 1.27 1.27)) hide)
    )
    (property "Value" "GND" (at 353.695 182.245 0)
      (effects (font (size 1.27 1.27) (thickness 0.15)) (justify left bottom))
    )
    (property "Footprint" "" (at 355.6 177.8 0)
      (effects (font (size 1.27 1.27) (thickness 0.15)) (justify left bottom) hide)
    )
    (property "Datasheet" "" (at 355.6 177.8 0)
      (effects (font (size 1.27 1.27) (thickness 0.15)) (justify left bottom) hide)
    )
    (property "Author" "Antmicro" (at 364.49 185.42 0)
      (effects (font (size 1.27 1.27) (thickness 0.15)) (justify left bottom) hide)
    )
    (property "License" "Apache-2.0" (at 364.49 187.96 0)
      (effects (font (size 1.27 1.27) (thickness 0.15)) (justify left bottom) hide)
    )
    (pin "1")
    (instances
      (project "antmicro-hdmi-mipi-bridge-hw"
        (path ""
          (reference "#PWR0180") (unit 1)
        )
      )
    )
  )

  (symbol (lib_id "antmicroCapacitors0603:C_4u7_0603") (at 234.95 234.95 90) (unit 1)
    (in_bom yes) (on_board yes) (dnp no) (fields_autoplaced)
    (property "Reference" "C52" (at 237.49 231.1336 90)
      (effects (font (size 1.524 1.524)) (justify right))
    )
    (property "Value" "C_4u7_0603" (at 245.11 214.63 0)
      (effects (font (size 1.27 1.27) (thickness 0.15)) (justify left bottom) hide)
    )
    (property "Footprint" "antmicro-footprints:C_0603_1608Metric" (at 247.65 214.63 0)
      (effects (font (size 1.27 1.27) (thickness 0.15)) (justify left bottom) hide)
    )
    (property "Datasheet" "https://product.tdk.com/en/search/capacitor/ceramic/mlcc/info?part_no=C1608X5R1V475M080AC" (at 250.19 214.63 0)
      (effects (font (size 1.27 1.27) (thickness 0.15)) (justify left bottom) hide)
    )
    (property "Manufacturer" "TDK" (at 255.27 214.63 0)
      (effects (font (size 1.27 1.27) (thickness 0.15)) (justify left bottom) hide)
    )
    (property "MPN" "C1608X5R1V475M080AC" (at 252.73 214.63 0)
      (effects (font (size 1.27 1.27) (thickness 0.15)) (justify left bottom) hide)
    )
    (property "Val" "4u7" (at 237.49 233.6736 90)
      (effects (font (size 1.27 1.27) (thickness 0.15)) (justify right))
    )
    (property "License" "Apache-2.0" (at 257.81 214.63 0)
      (effects (font (size 1.27 1.27) (thickness 0.15)) (justify left bottom) hide)
    )
    (property "Author" "Antmicro" (at 260.35 214.63 0)
      (effects (font (size 1.27 1.27) (thickness 0.15)) (justify left bottom) hide)
    )
    (property "Voltage" "" (at 262.89 214.63 0)
      (effects (font (size 1.27 1.27)) (justify left bottom) hide)
    )
    (property "Dielectric" "" (at 265.43 214.63 0)
      (effects (font (size 1.27 1.27)) (justify left bottom) hide)
    )
    (property "Public" "False" (at 267.97 214.63 0)
      (effects (font (size 1.27 1.27)) (justify left bottom) hide)
    )
    (pin "1")
    (pin "2")
    (instances
      (project "antmicro-hdmi-mipi-bridge-hw"
        (path ""
          (reference "C52") (unit 1)
        )
      )
    )
  )

  (symbol (lib_id "antmicropower:GND") (at 383.54 95.25 0) (unit 1)
    (in_bom yes) (on_board yes) (dnp no)
    (property "Reference" "#PWR0170" (at 383.54 101.6 0)
      (effects (font (size 1.27 1.27)) hide)
    )
    (property "Value" "GND" (at 387.35 96.52 0)
      (effects (font (size 1.27 1.27) (thickness 0.15)) (justify left bottom))
    )
    (property "Footprint" "" (at 383.54 95.25 0)
      (effects (font (size 1.27 1.27) (thickness 0.15)) (justify left bottom) hide)
    )
    (property "Datasheet" "" (at 383.54 95.25 0)
      (effects (font (size 1.27 1.27) (thickness 0.15)) (justify left bottom) hide)
    )
    (property "Author" "Antmicro" (at 392.43 102.87 0)
      (effects (font (size 1.27 1.27) (thickness 0.15)) (justify left bottom) hide)
    )
    (property "License" "Apache-2.0" (at 392.43 105.41 0)
      (effects (font (size 1.27 1.27) (thickness 0.15)) (justify left bottom) hide)
    )
    (pin "1")
    (instances
      (project "antmicro-hdmi-mipi-bridge-hw"
        (path ""
          (reference "#PWR0170") (unit 1)
        )
      )
    )
  )

  (symbol (lib_id "antmicroCapacitors0402:C_470p_0402") (at 223.52 214.63 270) (unit 1)
    (in_bom yes) (on_board yes) (dnp no)
    (property "Reference" "C47" (at 220.98 215.9 90)
      (effects (font (size 1.524 1.524)) (justify right))
    )
    (property "Value" "C_470p_0402" (at 213.36 234.95 0)
      (effects (font (size 1.27 1.27) (thickness 0.15)) (justify left bottom) hide)
    )
    (property "Footprint" "antmicro-footprints:C_0402_1005Metric" (at 210.82 234.95 0)
      (effects (font (size 1.27 1.27) (thickness 0.15)) (justify left bottom) hide)
    )
    (property "Datasheet" "https://www.passivecomponent.com/wp-content/uploads/datasheet/WTC_MLCC_General_Purpose.pdf" (at 208.28 234.95 0)
      (effects (font (size 1.27 1.27) (thickness 0.15)) (justify left bottom) hide)
    )
    (property "Manufacturer" "Walsin" (at 203.2 234.95 0)
      (effects (font (size 1.27 1.27) (thickness 0.15)) (justify left bottom) hide)
    )
    (property "MPN" "0402B471K250CT" (at 205.74 234.95 0)
      (effects (font (size 1.27 1.27) (thickness 0.15)) (justify left bottom) hide)
    )
    (property "Val" "470p" (at 216.535 219.075 90)
      (effects (font (size 1.27 1.27) (thickness 0.15)) (justify left bottom))
    )
    (property "License" "Apache-2.0" (at 200.66 234.95 0)
      (effects (font (size 1.27 1.27) (thickness 0.15)) (justify left bottom) hide)
    )
    (property "Author" "Antmicro" (at 198.12 234.95 0)
      (effects (font (size 1.27 1.27) (thickness 0.15)) (justify left bottom) hide)
    )
    (property "Voltage" "" (at 195.58 234.95 0)
      (effects (font (size 1.27 1.27)) (justify left bottom) hide)
    )
    (property "Dielectric" "" (at 193.04 234.95 0)
      (effects (font (size 1.27 1.27)) (justify left bottom) hide)
    )
    (property "Public" "False" (at 190.5 234.95 0)
      (effects (font (size 1.27 1.27)) (justify left bottom) hide)
    )
    (pin "1")
    (pin "2")
    (instances
      (project "antmicro-hdmi-mipi-bridge-hw"
        (path ""
          (reference "C47") (unit 1)
        )
      )
    )
  )

  (symbol (lib_id "antmicroResistors0603:R_0R_0603") (at 121.92 99.06 180) (unit 1)
    (in_bom yes) (on_board yes) (dnp no)
    (property "Reference" "R14" (at 119.38 94.615 0)
      (effects (font (size 1.524 1.524)))
    )
    (property "Value" "R_0R_0603" (at 101.6 86.36 0)
      (effects (font (size 1.27 1.27) (thickness 0.15)) (justify left bottom) hide)
    )
    (property "Footprint" "antmicro-footprints:R_0603_1608Metric" (at 101.6 83.82 0)
      (effects (font (size 1.27 1.27) (thickness 0.15)) (justify left bottom) hide)
    )
    (property "Datasheet" "https://www.bourns.com/docs/product-datasheets/cr.pdf?sfvrsn=574d41f6_14" (at 101.6 81.28 0)
      (effects (font (size 1.27 1.27) (thickness 0.15)) (justify left bottom) hide)
    )
    (property "Manufacturer" "Bourns" (at 101.6 76.2 0)
      (effects (font (size 1.27 1.27) (thickness 0.15)) (justify left bottom) hide)
    )
    (property "MPN" "CR0603-J/-000ELF" (at 101.6 78.74 0)
      (effects (font (size 1.27 1.27) (thickness 0.15)) (justify left bottom) hide)
    )
    (property "Val" "0R" (at 120.65 95.885 0)
      (effects (font (size 1.27 1.27) (thickness 0.15)) (justify left bottom))
    )
    (property "License" "Apache-2.0" (at 101.6 73.66 0)
      (effects (font (size 1.27 1.27) (thickness 0.15)) (justify left bottom) hide)
    )
    (property "Author" "Antmicro" (at 101.6 71.12 0)
      (effects (font (size 1.27 1.27) (thickness 0.15)) (justify left bottom) hide)
    )
    (property "Tolerance" "~" (at 101.6 88.9 0)
      (effects (font (size 1.27 1.27)) (justify left bottom) hide)
    )
    (property "Current" "1A" (at 101.6 68.58 0)
      (effects (font (size 1.27 1.27) (thickness 0.15)) (justify left bottom) hide)
    )
    (property "Public" "False" (at 101.6 68.58 0)
      (effects (font (size 1.27 1.27)) (justify left bottom) hide)
    )
    (pin "1")
    (pin "2")
    (instances
      (project "antmicro-hdmi-mipi-bridge-hw"
        (path ""
          (reference "R14") (unit 1)
        )
      )
    )
  )

  (symbol (lib_id "antmicropower:PWR_FLAG") (at 215.265 241.935 0) (unit 1)
    (in_bom yes) (on_board yes) (dnp no)
    (property "Reference" "#FLG0117" (at 215.265 240.03 0)
      (effects (font (size 1.27 1.27)) hide)
    )
    (property "Value" "PWR_FLAG" (at 210.185 238.125 0)
      (effects (font (size 1.27 1.27)) (justify left))
    )
    (property "Footprint" "" (at 215.265 241.935 0)
      (effects (font (size 1.27 1.27)) hide)
    )
    (property "Datasheet" "" (at 215.265 241.935 0)
      (effects (font (size 1.27 1.27)) hide)
    )
    (pin "1")
    (instances
      (project "antmicro-hdmi-mipi-bridge-hw"
        (path ""
          (reference "#FLG0117") (unit 1)
        )
      )
    )
  )

  (symbol (lib_id "antmicroTestPoints:TP_0.75mm_SMD") (at 106.68 199.39 0) (unit 1)
    (in_bom no) (on_board yes) (dnp no) (fields_autoplaced)
    (property "Reference" "TP5" (at 111.76 199.3899 0)
      (effects (font (size 1.27 1.27)) (justify left))
    )
    (property "Value" "TP_0.75mm_SMD" (at 121.92 207.01 0)
      (effects (font (size 1.27 1.27) (thickness 0.15)) (justify left bottom) hide)
    )
    (property "Footprint" "antmicro-footprints:TP_SMD_0.75mm" (at 121.92 209.55 0)
      (effects (font (size 1.27 1.27) (thickness 0.15)) (justify left bottom) hide)
    )
    (property "Datasheet" "" (at 121.92 212.09 0)
      (effects (font (size 1.27 1.27) (thickness 0.15)) (justify left bottom) hide)
    )
    (property "MPN" "" (at 106.68 199.39 0)
      (effects (font (size 1.27 1.27) (thickness 0.15)) (justify left bottom) hide)
    )
    (property "Manufacturer" "" (at 106.68 199.39 0)
      (effects (font (size 1.27 1.27) (thickness 0.15)) (justify left bottom) hide)
    )
    (property "Author" "Antmicro" (at 121.92 214.63 0)
      (effects (font (size 1.27 1.27) (thickness 0.15)) (justify left bottom) hide)
    )
    (property "License" "Apache-2.0" (at 121.92 217.17 0)
      (effects (font (size 1.27 1.27) (thickness 0.15)) (justify left bottom) hide)
    )
    (property "Public" "False" (at 116.84 213.36 0)
      (effects (font (size 1.27 1.27)) (justify left bottom) hide)
    )
    (pin "1")
    (instances
      (project "antmicro-hdmi-mipi-bridge-hw"
        (path ""
          (reference "TP5") (unit 1)
        )
      )
    )
  )

  (symbol (lib_id "antmicroResistors0402:R_10k_0402") (at 149.86 193.04 90) (unit 1)
    (in_bom yes) (on_board yes) (dnp no)
    (property "Reference" "R16" (at 143.51 189.23 90)
      (effects (font (size 1.524 1.524)) (justify right))
    )
    (property "Value" "R_10k_0402" (at 162.56 172.72 0)
      (effects (font (size 1.27 1.27) (thickness 0.15)) (justify left bottom) hide)
    )
    (property "Footprint" "antmicro-footprints:R_0402_1005Metric" (at 165.1 172.72 0)
      (effects (font (size 1.27 1.27) (thickness 0.15)) (justify left bottom) hide)
    )
    (property "Datasheet" "https://www.bourns.com/docs/product-datasheets/cr.pdf" (at 167.64 172.72 0)
      (effects (font (size 1.27 1.27) (thickness 0.15)) (justify left bottom) hide)
    )
    (property "Manufacturer" "Bourns" (at 172.72 172.72 0)
      (effects (font (size 1.27 1.27) (thickness 0.15)) (justify left bottom) hide)
    )
    (property "MPN" "CR0402-FX-1002GLF" (at 170.18 172.72 0)
      (effects (font (size 1.27 1.27) (thickness 0.15)) (justify left bottom) hide)
    )
    (property "Val" "10k" (at 147.955 191.135 90)
      (effects (font (size 1.27 1.27) (thickness 0.15)) (justify left bottom))
    )
    (property "License" "Apache-2.0" (at 175.26 172.72 0)
      (effects (font (size 1.27 1.27) (thickness 0.15)) (justify left bottom) hide)
    )
    (property "Author" "Antmicro" (at 177.8 172.72 0)
      (effects (font (size 1.27 1.27) (thickness 0.15)) (justify left bottom) hide)
    )
    (property "Tolerance" "1%" (at 160.02 172.72 0)
      (effects (font (size 1.27 1.27)) (justify left bottom) hide)
    )
    (property "Public" "False" (at 180.34 172.72 0)
      (effects (font (size 1.27 1.27)) (justify left bottom) hide)
    )
    (pin "1")
    (pin "2")
    (instances
      (project "antmicro-hdmi-mipi-bridge-hw"
        (path ""
          (reference "R16") (unit 1)
        )
      )
    )
  )

  (symbol (lib_id "antmicropower:GND") (at 234.95 222.25 0) (unit 1)
    (in_bom yes) (on_board yes) (dnp no)
    (property "Reference" "#PWR0161" (at 234.95 228.6 0)
      (effects (font (size 1.27 1.27)) hide)
    )
    (property "Value" "GND" (at 236.855 224.79 0)
      (effects (font (size 1.27 1.27) (thickness 0.15)) (justify left bottom))
    )
    (property "Footprint" "" (at 234.95 222.25 0)
      (effects (font (size 1.27 1.27) (thickness 0.15)) (justify left bottom) hide)
    )
    (property "Datasheet" "" (at 234.95 222.25 0)
      (effects (font (size 1.27 1.27) (thickness 0.15)) (justify left bottom) hide)
    )
    (property "Author" "Antmicro" (at 243.84 229.87 0)
      (effects (font (size 1.27 1.27) (thickness 0.15)) (justify left bottom) hide)
    )
    (property "License" "Apache-2.0" (at 243.84 232.41 0)
      (effects (font (size 1.27 1.27) (thickness 0.15)) (justify left bottom) hide)
    )
    (pin "1")
    (instances
      (project "antmicro-hdmi-mipi-bridge-hw"
        (path ""
          (reference "#PWR0161") (unit 1)
        )
      )
    )
  )

  (symbol (lib_id "antmicropower:GND") (at 304.8 49.53 0) (unit 1)
    (in_bom yes) (on_board yes) (dnp no)
    (property "Reference" "#PWR0174" (at 304.8 55.88 0)
      (effects (font (size 1.27 1.27)) hide)
    )
    (property "Value" "GND" (at 302.895 53.975 0)
      (effects (font (size 1.27 1.27) (thickness 0.15)) (justify left bottom))
    )
    (property "Footprint" "" (at 304.8 49.53 0)
      (effects (font (size 1.27 1.27) (thickness 0.15)) (justify left bottom) hide)
    )
    (property "Datasheet" "" (at 304.8 49.53 0)
      (effects (font (size 1.27 1.27) (thickness 0.15)) (justify left bottom) hide)
    )
    (property "Author" "Antmicro" (at 313.69 57.15 0)
      (effects (font (size 1.27 1.27) (thickness 0.15)) (justify left bottom) hide)
    )
    (property "License" "Apache-2.0" (at 313.69 59.69 0)
      (effects (font (size 1.27 1.27) (thickness 0.15)) (justify left bottom) hide)
    )
    (pin "1")
    (instances
      (project "antmicro-hdmi-mipi-bridge-hw"
        (path ""
          (reference "#PWR0174") (unit 1)
        )
      )
    )
  )

  (symbol (lib_id "antmicropower:GND") (at 223.52 237.49 0) (unit 1)
    (in_bom yes) (on_board yes) (dnp no)
    (property "Reference" "#PWR0186" (at 223.52 243.84 0)
      (effects (font (size 1.27 1.27)) hide)
    )
    (property "Value" "GND" (at 225.425 240.03 0)
      (effects (font (size 1.27 1.27) (thickness 0.15)) (justify left bottom))
    )
    (property "Footprint" "" (at 223.52 237.49 0)
      (effects (font (size 1.27 1.27) (thickness 0.15)) (justify left bottom) hide)
    )
    (property "Datasheet" "" (at 223.52 237.49 0)
      (effects (font (size 1.27 1.27) (thickness 0.15)) (justify left bottom) hide)
    )
    (property "Author" "Antmicro" (at 232.41 245.11 0)
      (effects (font (size 1.27 1.27) (thickness 0.15)) (justify left bottom) hide)
    )
    (property "License" "Apache-2.0" (at 232.41 247.65 0)
      (effects (font (size 1.27 1.27) (thickness 0.15)) (justify left bottom) hide)
    )
    (pin "1")
    (instances
      (project "antmicro-hdmi-mipi-bridge-hw"
        (path ""
          (reference "#PWR0186") (unit 1)
        )
      )
    )
  )

  (symbol (lib_id "antmicropower:GND") (at 116.84 83.82 0) (unit 1)
    (in_bom yes) (on_board yes) (dnp no)
    (property "Reference" "#PWR0144" (at 116.84 90.17 0)
      (effects (font (size 1.27 1.27)) hide)
    )
    (property "Value" "GND" (at 114.935 88.265 0)
      (effects (font (size 1.27 1.27) (thickness 0.15)) (justify left bottom))
    )
    (property "Footprint" "" (at 116.84 83.82 0)
      (effects (font (size 1.27 1.27) (thickness 0.15)) (justify left bottom) hide)
    )
    (property "Datasheet" "" (at 116.84 83.82 0)
      (effects (font (size 1.27 1.27) (thickness 0.15)) (justify left bottom) hide)
    )
    (property "Author" "Antmicro" (at 125.73 91.44 0)
      (effects (font (size 1.27 1.27) (thickness 0.15)) (justify left bottom) hide)
    )
    (property "License" "Apache-2.0" (at 125.73 93.98 0)
      (effects (font (size 1.27 1.27) (thickness 0.15)) (justify left bottom) hide)
    )
    (pin "1")
    (instances
      (project "antmicro-hdmi-mipi-bridge-hw"
        (path ""
          (reference "#PWR0144") (unit 1)
        )
      )
    )
  )

  (symbol (lib_id "antmicropower:GND") (at 332.74 186.69 0) (unit 1)
    (in_bom yes) (on_board yes) (dnp no)
    (property "Reference" "#PWR0179" (at 332.74 193.04 0)
      (effects (font (size 1.27 1.27)) hide)
    )
    (property "Value" "GND" (at 330.835 191.135 0)
      (effects (font (size 1.27 1.27) (thickness 0.15)) (justify left bottom))
    )
    (property "Footprint" "" (at 332.74 186.69 0)
      (effects (font (size 1.27 1.27) (thickness 0.15)) (justify left bottom) hide)
    )
    (property "Datasheet" "" (at 332.74 186.69 0)
      (effects (font (size 1.27 1.27) (thickness 0.15)) (justify left bottom) hide)
    )
    (property "Author" "Antmicro" (at 341.63 194.31 0)
      (effects (font (size 1.27 1.27) (thickness 0.15)) (justify left bottom) hide)
    )
    (property "License" "Apache-2.0" (at 341.63 196.85 0)
      (effects (font (size 1.27 1.27) (thickness 0.15)) (justify left bottom) hide)
    )
    (pin "1")
    (instances
      (project "antmicro-hdmi-mipi-bridge-hw"
        (path ""
          (reference "#PWR0179") (unit 1)
        )
      )
    )
  )

  (symbol (lib_id "antmicropower:GND") (at 294.64 49.53 0) (unit 1)
    (in_bom yes) (on_board yes) (dnp no)
    (property "Reference" "#PWR0175" (at 294.64 55.88 0)
      (effects (font (size 1.27 1.27)) hide)
    )
    (property "Value" "GND" (at 292.735 53.975 0)
      (effects (font (size 1.27 1.27) (thickness 0.15)) (justify left bottom))
    )
    (property "Footprint" "" (at 294.64 49.53 0)
      (effects (font (size 1.27 1.27) (thickness 0.15)) (justify left bottom) hide)
    )
    (property "Datasheet" "" (at 294.64 49.53 0)
      (effects (font (size 1.27 1.27) (thickness 0.15)) (justify left bottom) hide)
    )
    (property "Author" "Antmicro" (at 303.53 57.15 0)
      (effects (font (size 1.27 1.27) (thickness 0.15)) (justify left bottom) hide)
    )
    (property "License" "Apache-2.0" (at 303.53 59.69 0)
      (effects (font (size 1.27 1.27) (thickness 0.15)) (justify left bottom) hide)
    )
    (pin "1")
    (instances
      (project "antmicro-hdmi-mipi-bridge-hw"
        (path ""
          (reference "#PWR0175") (unit 1)
        )
      )
    )
  )

  (symbol (lib_id "antmicropower:GND") (at 355.6 210.82 0) (unit 1)
    (in_bom yes) (on_board yes) (dnp no)
    (property "Reference" "#PWR0178" (at 355.6 217.17 0)
      (effects (font (size 1.27 1.27)) hide)
    )
    (property "Value" "GND" (at 353.695 215.265 0)
      (effects (font (size 1.27 1.27) (thickness 0.15)) (justify left bottom))
    )
    (property "Footprint" "" (at 355.6 210.82 0)
      (effects (font (size 1.27 1.27) (thickness 0.15)) (justify left bottom) hide)
    )
    (property "Datasheet" "" (at 355.6 210.82 0)
      (effects (font (size 1.27 1.27) (thickness 0.15)) (justify left bottom) hide)
    )
    (property "Author" "Antmicro" (at 364.49 218.44 0)
      (effects (font (size 1.27 1.27) (thickness 0.15)) (justify left bottom) hide)
    )
    (property "License" "Apache-2.0" (at 364.49 220.98 0)
      (effects (font (size 1.27 1.27) (thickness 0.15)) (justify left bottom) hide)
    )
    (pin "1")
    (instances
      (project "antmicro-hdmi-mipi-bridge-hw"
        (path ""
          (reference "#PWR0178") (unit 1)
        )
      )
    )
  )

  (symbol (lib_id "antmicroCapacitors0402:C_100n_0402") (at 383.54 92.71 90) (unit 1)
    (in_bom yes) (on_board yes) (dnp no) (fields_autoplaced)
    (property "Reference" "C45" (at 386.08 88.8936 90)
      (effects (font (size 1.524 1.524)) (justify right))
    )
    (property "Value" "C_100n_0402" (at 393.7 72.39 0)
      (effects (font (size 1.27 1.27) (thickness 0.15)) (justify left bottom) hide)
    )
    (property "Footprint" "antmicro-footprints:C_0402_1005Metric" (at 396.24 72.39 0)
      (effects (font (size 1.27 1.27) (thickness 0.15)) (justify left bottom) hide)
    )
    (property "Datasheet" "https://www.murata.com/products/productdetail?partno=GRM155R61H104KE14%23" (at 398.78 72.39 0)
      (effects (font (size 1.27 1.27) (thickness 0.15)) (justify left bottom) hide)
    )
    (property "Manufacturer" "Murata" (at 403.86 72.39 0)
      (effects (font (size 1.27 1.27) (thickness 0.15)) (justify left bottom) hide)
    )
    (property "MPN" "GRM155R61H104KE14D" (at 401.32 72.39 0)
      (effects (font (size 1.27 1.27) (thickness 0.15)) (justify left bottom) hide)
    )
    (property "Val" "100n" (at 386.08 91.4336 90)
      (effects (font (size 1.27 1.27) (thickness 0.15)) (justify right))
    )
    (property "License" "Apache-2.0" (at 406.4 72.39 0)
      (effects (font (size 1.27 1.27) (thickness 0.15)) (justify left bottom) hide)
    )
    (property "Author" "Antmicro" (at 408.94 72.39 0)
      (effects (font (size 1.27 1.27) (thickness 0.15)) (justify left bottom) hide)
    )
    (property "Voltage" "50V" (at 411.48 72.39 0)
      (effects (font (size 1.27 1.27)) (justify left bottom) hide)
    )
    (property "Dielectric" "X5R" (at 414.02 72.39 0)
      (effects (font (size 1.27 1.27)) (justify left bottom) hide)
    )
    (property "Public" "False" (at 416.56 72.39 0)
      (effects (font (size 1.27 1.27)) (justify left bottom) hide)
    )
    (pin "1")
    (pin "2")
    (instances
      (project "antmicro-hdmi-mipi-bridge-hw"
        (path ""
          (reference "C45") (unit 1)
        )
      )
    )
  )

  (symbol (lib_id "antmicropower:PWR_FLAG") (at 215.265 196.215 0) (unit 1)
    (in_bom yes) (on_board yes) (dnp no)
    (property "Reference" "#FLG0115" (at 215.265 194.31 0)
      (effects (font (size 1.27 1.27)) hide)
    )
    (property "Value" "PWR_FLAG" (at 210.185 192.405 0)
      (effects (font (size 1.27 1.27)) (justify left))
    )
    (property "Footprint" "" (at 215.265 196.215 0)
      (effects (font (size 1.27 1.27)) hide)
    )
    (property "Datasheet" "" (at 215.265 196.215 0)
      (effects (font (size 1.27 1.27)) hide)
    )
    (pin "1")
    (instances
      (project "antmicro-hdmi-mipi-bridge-hw"
        (path ""
          (reference "#FLG0115") (unit 1)
        )
      )
    )
  )

  (symbol (lib_id "antmicropower:+3V3") (at 240.03 165.1 0) (unit 1)
    (in_bom yes) (on_board yes) (dnp no) (fields_autoplaced)
    (property "Reference" "#PWR0190" (at 240.03 168.91 0)
      (effects (font (size 1.27 1.27)) hide)
    )
    (property "Value" "+3V3" (at 240.03 160.02 0)
      (effects (font (size 1.27 1.27) (thickness 0.15)) (justify left bottom))
    )
    (property "Footprint" "" (at 240.03 165.1 0)
      (effects (font (size 1.27 1.27) (thickness 0.15)) (justify left bottom) hide)
    )
    (property "Datasheet" "" (at 240.03 165.1 0)
      (effects (font (size 1.27 1.27) (thickness 0.15)) (justify left bottom) hide)
    )
    (property "Author" "Antmicro" (at 255.27 167.64 0)
      (effects (font (size 1.27 1.27) (thickness 0.15)) (justify left bottom) hide)
    )
    (property "License" "Apache-2.0" (at 255.27 170.18 0)
      (effects (font (size 1.27 1.27) (thickness 0.15)) (justify left bottom) hide)
    )
    (pin "1")
    (instances
      (project "antmicro-hdmi-mipi-bridge-hw"
        (path ""
          (reference "#PWR0190") (unit 1)
        )
      )
    )
  )

  (symbol (lib_id "antmicroFerriteBeadsandChips:FB_120Z_3A_Murata-BLM18SG_0603") (at 78.74 90.805 90) (unit 1)
    (in_bom yes) (on_board yes) (dnp no)
    (property "Reference" "FB7" (at 83.82 85.725 90)
      (effects (font (size 1.524 1.524)))
    )
    (property "Value" "FB_120Z_3A_Murata-BLM18SG_0603" (at 81.28 76.835 0)
      (effects (font (size 1.27 1.27) (thickness 0.15)) (justify left bottom) hide)
    )
    (property "Footprint" "antmicro-footprints:FB_0603_1608Metric" (at 86.36 76.835 0)
      (effects (font (size 1.27 1.27) (thickness 0.15)) (justify left bottom) hide)
    )
    (property "Datasheet" "https://www.murata.com/products/productdata/8796738650142/ENFA0003.pdf?1681308024000" (at 88.9 76.835 0)
      (effects (font (size 1.27 1.27) (thickness 0.15)) (justify left bottom) hide)
    )
    (property "MPN" "BLM18SG121TN1D" (at 91.44 76.835 0)
      (effects (font (size 1.27 1.27) (thickness 0.15)) (justify left bottom) hide)
    )
    (property "Manufacturer" "Murata" (at 93.98 76.835 0)
      (effects (font (size 1.27 1.27) (thickness 0.15)) (justify left bottom) hide)
    )
    (property "Author" "Antmicro" (at 96.52 76.835 0)
      (effects (font (size 1.27 1.27) (thickness 0.15)) (justify left bottom) hide)
    )
    (property "License" "Apache-2.0" (at 99.06 76.835 0)
      (effects (font (size 1.27 1.27) (thickness 0.15)) (justify left bottom) hide)
    )
    (property "Val" "120Z/3A" (at 90.17 87.63 90)
      (effects (font (size 1.27 1.27)) (justify left bottom))
    )
    (property "Current" "" (at 101.6 70.485 0)
      (effects (font (size 1.27 1.27) (thickness 0.15)) (justify left bottom) hide)
    )
    (property "Public" "False" (at 93.98 70.485 0)
      (effects (font (size 1.27 1.27)) (justify left bottom) hide)
    )
    (pin "1")
    (pin "2")
    (instances
      (project "antmicro-hdmi-mipi-bridge-hw"
        (path ""
          (reference "FB7") (unit 1)
        )
      )
    )
  )

  (symbol (lib_id "antmicropower:PWR_FLAG") (at 215.265 259.715 0) (unit 1)
    (in_bom yes) (on_board yes) (dnp no)
    (property "Reference" "#FLG0118" (at 215.265 257.81 0)
      (effects (font (size 1.27 1.27)) hide)
    )
    (property "Value" "PWR_FLAG" (at 210.185 255.905 0)
      (effects (font (size 1.27 1.27)) (justify left))
    )
    (property "Footprint" "" (at 215.265 259.715 0)
      (effects (font (size 1.27 1.27)) hide)
    )
    (property "Datasheet" "" (at 215.265 259.715 0)
      (effects (font (size 1.27 1.27)) hide)
    )
    (pin "1")
    (instances
      (project "antmicro-hdmi-mipi-bridge-hw"
        (path ""
          (reference "#FLG0118") (unit 1)
        )
      )
    )
  )

  (symbol (lib_id "antmicropower:PWR_FLAG") (at 215.265 226.695 0) (unit 1)
    (in_bom yes) (on_board yes) (dnp no)
    (property "Reference" "#FLG0114" (at 215.265 224.79 0)
      (effects (font (size 1.27 1.27)) hide)
    )
    (property "Value" "PWR_FLAG" (at 210.185 222.885 0)
      (effects (font (size 1.27 1.27)) (justify left))
    )
    (property "Footprint" "" (at 215.265 226.695 0)
      (effects (font (size 1.27 1.27)) hide)
    )
    (property "Datasheet" "" (at 215.265 226.695 0)
      (effects (font (size 1.27 1.27)) hide)
    )
    (pin "1")
    (instances
      (project "antmicro-hdmi-mipi-bridge-hw"
        (path ""
          (reference "#FLG0114") (unit 1)
        )
      )
    )
  )

  (symbol (lib_id "antmicroPMICVoltageRegulatorsLinear:TLV73325PDBVT") (at 334.01 173.99 0) (unit 1)
    (in_bom yes) (on_board yes) (dnp no)
    (property "Reference" "IC3" (at 344.17 167.64 0)
      (effects (font (size 1.27 1.27)))
    )
    (property "Value" "TLV73325PDBVT" (at 336.55 170.815 0)
      (effects (font (size 1.27 1.27) (thickness 0.15)) (justify left bottom) hide)
    )
    (property "Footprint" "antmicro-footprints:SOT-23-5" (at 369.57 181.61 0)
      (effects (font (size 1.27 1.27) (thickness 0.15)) (justify left bottom) hide)
    )
    (property "Datasheet" "https://www.ti.com/lit/ds/symlink/tlv733p.pdf?HQS=dis-mous-null-mousermode-dsf-pf-null-wwe&ts=1676978230940&ref_url=https%253A%252F%252Fwww.mouser.com%252F" (at 369.57 184.15 0)
      (effects (font (size 1.27 1.27) (thickness 0.15)) (justify left bottom) hide)
    )
    (property "MPN" "TLV73325PDBVT" (at 336.55 170.815 0)
      (effects (font (size 1.27 1.27) (thickness 0.15)) (justify left bottom))
    )
    (property "Manufacturer" "Texas Instruments" (at 369.57 189.23 0)
      (effects (font (size 1.27 1.27) (thickness 0.15)) (justify left bottom) hide)
    )
    (property "Author" "Antmicro" (at 369.57 191.77 0)
      (effects (font (size 1.27 1.27) (thickness 0.15)) (justify left bottom) hide)
    )
    (property "License" "Apache-2.0" (at 369.57 194.31 0)
      (effects (font (size 1.27 1.27) (thickness 0.15)) (justify left bottom) hide)
    )
    (pin "1")
    (pin "2")
    (pin "3")
    (pin "4")
    (pin "5")
    (instances
      (project "antmicro-hdmi-mipi-bridge-hw"
        (path ""
          (reference "IC3") (unit 1)
        )
      )
    )
  )

  (symbol (lib_id "antmicropower:GND") (at 102.87 260.35 0) (unit 1)
    (in_bom yes) (on_board yes) (dnp no)
    (property "Reference" "#PWR0151" (at 102.87 266.7 0)
      (effects (font (size 1.27 1.27)) hide)
    )
    (property "Value" "GND" (at 100.965 265.43 0)
      (effects (font (size 1.27 1.27) (thickness 0.15)) (justify left bottom))
    )
    (property "Footprint" "" (at 102.87 260.35 0)
      (effects (font (size 1.27 1.27) (thickness 0.15)) (justify left bottom) hide)
    )
    (property "Datasheet" "" (at 102.87 260.35 0)
      (effects (font (size 1.27 1.27) (thickness 0.15)) (justify left bottom) hide)
    )
    (property "Author" "Antmicro" (at 111.76 267.97 0)
      (effects (font (size 1.27 1.27) (thickness 0.15)) (justify left bottom) hide)
    )
    (property "License" "Apache-2.0" (at 111.76 270.51 0)
      (effects (font (size 1.27 1.27) (thickness 0.15)) (justify left bottom) hide)
    )
    (pin "1")
    (instances
      (project "antmicro-hdmi-mipi-bridge-hw"
        (path ""
          (reference "#PWR0151") (unit 1)
        )
      )
    )
  )

  (symbol (lib_id "antmicropower:GND") (at 360.68 219.71 0) (unit 1)
    (in_bom yes) (on_board yes) (dnp no)
    (property "Reference" "#PWR0177" (at 360.68 226.06 0)
      (effects (font (size 1.27 1.27)) hide)
    )
    (property "Value" "GND" (at 358.775 224.155 0)
      (effects (font (size 1.27 1.27) (thickness 0.15)) (justify left bottom))
    )
    (property "Footprint" "" (at 360.68 219.71 0)
      (effects (font (size 1.27 1.27) (thickness 0.15)) (justify left bottom) hide)
    )
    (property "Datasheet" "" (at 360.68 219.71 0)
      (effects (font (size 1.27 1.27) (thickness 0.15)) (justify left bottom) hide)
    )
    (property "Author" "Antmicro" (at 369.57 227.33 0)
      (effects (font (size 1.27 1.27) (thickness 0.15)) (justify left bottom) hide)
    )
    (property "License" "Apache-2.0" (at 369.57 229.87 0)
      (effects (font (size 1.27 1.27) (thickness 0.15)) (justify left bottom) hide)
    )
    (pin "1")
    (instances
      (project "antmicro-hdmi-mipi-bridge-hw"
        (path ""
          (reference "#PWR0177") (unit 1)
        )
      )
    )
  )

  (symbol (lib_id "antmicropower:GND") (at 90.17 81.28 0) (unit 1)
    (in_bom yes) (on_board yes) (dnp no)
    (property "Reference" "#PWR0146" (at 90.17 87.63 0)
      (effects (font (size 1.27 1.27)) hide)
    )
    (property "Value" "GND" (at 88.265 85.725 0)
      (effects (font (size 1.27 1.27) (thickness 0.15)) (justify left bottom))
    )
    (property "Footprint" "" (at 90.17 81.28 0)
      (effects (font (size 1.27 1.27) (thickness 0.15)) (justify left bottom) hide)
    )
    (property "Datasheet" "" (at 90.17 81.28 0)
      (effects (font (size 1.27 1.27) (thickness 0.15)) (justify left bottom) hide)
    )
    (property "Author" "Antmicro" (at 99.06 88.9 0)
      (effects (font (size 1.27 1.27) (thickness 0.15)) (justify left bottom) hide)
    )
    (property "License" "Apache-2.0" (at 99.06 91.44 0)
      (effects (font (size 1.27 1.27) (thickness 0.15)) (justify left bottom) hide)
    )
    (pin "1")
    (instances
      (project "antmicro-hdmi-mipi-bridge-hw"
        (path ""
          (reference "#PWR0146") (unit 1)
        )
      )
    )
  )

  (symbol (lib_id "antmicropower:GND") (at 360.68 186.69 0) (unit 1)
    (in_bom yes) (on_board yes) (dnp no)
    (property "Reference" "#PWR0181" (at 360.68 193.04 0)
      (effects (font (size 1.27 1.27)) hide)
    )
    (property "Value" "GND" (at 358.775 191.135 0)
      (effects (font (size 1.27 1.27) (thickness 0.15)) (justify left bottom))
    )
    (property "Footprint" "" (at 360.68 186.69 0)
      (effects (font (size 1.27 1.27) (thickness 0.15)) (justify left bottom) hide)
    )
    (property "Datasheet" "" (at 360.68 186.69 0)
      (effects (font (size 1.27 1.27) (thickness 0.15)) (justify left bottom) hide)
    )
    (property "Author" "Antmicro" (at 369.57 194.31 0)
      (effects (font (size 1.27 1.27) (thickness 0.15)) (justify left bottom) hide)
    )
    (property "License" "Apache-2.0" (at 369.57 196.85 0)
      (effects (font (size 1.27 1.27) (thickness 0.15)) (justify left bottom) hide)
    )
    (pin "1")
    (instances
      (project "antmicro-hdmi-mipi-bridge-hw"
        (path ""
          (reference "#PWR0181") (unit 1)
        )
      )
    )
  )

  (symbol (lib_id "antmicropower:GND") (at 339.09 46.355 0) (unit 1)
    (in_bom yes) (on_board yes) (dnp no)
    (property "Reference" "#PWR0167" (at 339.09 52.705 0)
      (effects (font (size 1.27 1.27)) hide)
    )
    (property "Value" "GND" (at 337.185 50.8 0)
      (effects (font (size 1.27 1.27) (thickness 0.15)) (justify left bottom))
    )
    (property "Footprint" "" (at 339.09 46.355 0)
      (effects (font (size 1.27 1.27) (thickness 0.15)) (justify left bottom) hide)
    )
    (property "Datasheet" "" (at 339.09 46.355 0)
      (effects (font (size 1.27 1.27) (thickness 0.15)) (justify left bottom) hide)
    )
    (property "Author" "Antmicro" (at 347.98 53.975 0)
      (effects (font (size 1.27 1.27) (thickness 0.15)) (justify left bottom) hide)
    )
    (property "License" "Apache-2.0" (at 347.98 56.515 0)
      (effects (font (size 1.27 1.27) (thickness 0.15)) (justify left bottom) hide)
    )
    (pin "1")
    (instances
      (project "antmicro-hdmi-mipi-bridge-hw"
        (path ""
          (reference "#PWR0167") (unit 1)
        )
      )
    )
  )

  (symbol (lib_id "antmicropower:GND") (at 367.03 49.53 0) (unit 1)
    (in_bom yes) (on_board yes) (dnp no)
    (property "Reference" "#PWR0168" (at 367.03 55.88 0)
      (effects (font (size 1.27 1.27)) hide)
    )
    (property "Value" "GND" (at 365.125 53.975 0)
      (effects (font (size 1.27 1.27) (thickness 0.15)) (justify left bottom))
    )
    (property "Footprint" "" (at 367.03 49.53 0)
      (effects (font (size 1.27 1.27) (thickness 0.15)) (justify left bottom) hide)
    )
    (property "Datasheet" "" (at 367.03 49.53 0)
      (effects (font (size 1.27 1.27) (thickness 0.15)) (justify left bottom) hide)
    )
    (property "Author" "Antmicro" (at 375.92 57.15 0)
      (effects (font (size 1.27 1.27) (thickness 0.15)) (justify left bottom) hide)
    )
    (property "License" "Apache-2.0" (at 375.92 59.69 0)
      (effects (font (size 1.27 1.27) (thickness 0.15)) (justify left bottom) hide)
    )
    (pin "1")
    (instances
      (project "antmicro-hdmi-mipi-bridge-hw"
        (path ""
          (reference "#PWR0168") (unit 1)
        )
      )
    )
  )

  (symbol (lib_id "antmicropower:PWR_FLAG") (at 215.265 165.735 0) (unit 1)
    (in_bom yes) (on_board yes) (dnp no)
    (property "Reference" "#FLG0119" (at 215.265 163.83 0)
      (effects (font (size 1.27 1.27)) hide)
    )
    (property "Value" "PWR_FLAG" (at 210.185 161.925 0)
      (effects (font (size 1.27 1.27)) (justify left))
    )
    (property "Footprint" "" (at 215.265 165.735 0)
      (effects (font (size 1.27 1.27)) hide)
    )
    (property "Datasheet" "" (at 215.265 165.735 0)
      (effects (font (size 1.27 1.27)) hide)
    )
    (pin "1")
    (instances
      (project "antmicro-hdmi-mipi-bridge-hw"
        (path ""
          (reference "#FLG0119") (unit 1)
        )
      )
    )
  )

  (symbol (lib_id "antmicropower:+3V3") (at 305.435 82.55 0) (unit 1)
    (in_bom yes) (on_board yes) (dnp no)
    (property "Reference" "#PWR0163" (at 305.435 86.36 0)
      (effects (font (size 1.27 1.27)) hide)
    )
    (property "Value" "+3V3" (at 302.26 79.375 0)
      (effects (font (size 1.27 1.27) (thickness 0.15)) (justify left bottom))
    )
    (property "Footprint" "" (at 305.435 82.55 0)
      (effects (font (size 1.27 1.27) (thickness 0.15)) (justify left bottom) hide)
    )
    (property "Datasheet" "" (at 305.435 82.55 0)
      (effects (font (size 1.27 1.27) (thickness 0.15)) (justify left bottom) hide)
    )
    (property "Author" "Antmicro" (at 320.675 85.09 0)
      (effects (font (size 1.27 1.27) (thickness 0.15)) (justify left bottom) hide)
    )
    (property "License" "Apache-2.0" (at 320.675 87.63 0)
      (effects (font (size 1.27 1.27) (thickness 0.15)) (justify left bottom) hide)
    )
    (pin "1")
    (instances
      (project "antmicro-hdmi-mipi-bridge-hw"
        (path ""
          (reference "#PWR0163") (unit 1)
        )
      )
    )
  )

  (symbol (lib_id "antmicropower:GND") (at 223.52 252.73 0) (unit 1)
    (in_bom yes) (on_board yes) (dnp no)
    (property "Reference" "#PWR0162" (at 223.52 259.08 0)
      (effects (font (size 1.27 1.27)) hide)
    )
    (property "Value" "GND" (at 221.615 257.81 0)
      (effects (font (size 1.27 1.27) (thickness 0.15)) (justify left bottom))
    )
    (property "Footprint" "" (at 223.52 252.73 0)
      (effects (font (size 1.27 1.27) (thickness 0.15)) (justify left bottom) hide)
    )
    (property "Datasheet" "" (at 223.52 252.73 0)
      (effects (font (size 1.27 1.27) (thickness 0.15)) (justify left bottom) hide)
    )
    (property "Author" "Antmicro" (at 232.41 260.35 0)
      (effects (font (size 1.27 1.27) (thickness 0.15)) (justify left bottom) hide)
    )
    (property "License" "Apache-2.0" (at 232.41 262.89 0)
      (effects (font (size 1.27 1.27) (thickness 0.15)) (justify left bottom) hide)
    )
    (pin "1")
    (instances
      (project "antmicro-hdmi-mipi-bridge-hw"
        (path ""
          (reference "#PWR0162") (unit 1)
        )
      )
    )
  )

  (symbol (lib_id "antmicroOscillators:Oscillator_27MHz_TXC_7C") (at 340.36 39.37 0) (unit 1)
    (in_bom yes) (on_board yes) (dnp no)
    (property "Reference" "Y2" (at 349.885 33.02 0)
      (effects (font (size 1.27 1.27)))
    )
    (property "Value" "Oscillator_27MHz_TXC_7C" (at 365.76 51.435 0)
      (effects (font (size 1.27 1.27) (thickness 0.15)) (justify left bottom) hide)
    )
    (property "Footprint" "antmicro-footprints:Oscillator_SMD_TXC_7C_5x3.2x1.2mm" (at 365.76 53.975 0)
      (effects (font (size 1.27 1.27) (thickness 0.15)) (justify left bottom) hide)
    )
    (property "Datasheet" "http://www.txccorp.com/download/products/oscillators/2015TXC_7C_57.pdf" (at 365.76 56.515 0)
      (effects (font (size 1.27 1.27) (thickness 0.15)) (justify left bottom) hide)
    )
    (property "MPN" "7C-27.000MBB-T" (at 340.995 36.195 0)
      (effects (font (size 1.27 1.27) (thickness 0.15)) (justify left bottom))
    )
    (property "Manufacturer" "TXC" (at 365.76 46.355 0)
      (effects (font (size 1.27 1.27) (thickness 0.15)) (justify left bottom) hide)
    )
    (property "Author" "Antmicro" (at 365.76 59.055 0)
      (effects (font (size 1.27 1.27) (thickness 0.15)) (justify left bottom) hide)
    )
    (property "License" "Apache-2.0" (at 365.76 61.595 0)
      (effects (font (size 1.27 1.27) (thickness 0.15)) (justify left bottom) hide)
    )
    (property "Val" "27 MHz" (at 346.075 49.53 0)
      (effects (font (size 1.27 1.27) (thickness 0.15)) (justify left bottom))
    )
    (property "Public" "False" (at 372.11 63.5 0)
      (effects (font (size 1.27 1.27)) (justify left bottom) hide)
    )
    (pin "1")
    (pin "2")
    (pin "3")
    (pin "4")
    (instances
      (project "antmicro-hdmi-mipi-bridge-hw"
        (path ""
          (reference "Y2") (unit 1)
        )
      )
    )
  )

  (symbol (lib_id "antmicroCapacitors0603:C_10u_0603") (at 332.74 184.15 90) (unit 1)
    (in_bom yes) (on_board yes) (dnp no)
    (property "Reference" "C40" (at 339.09 184.15 90)
      (effects (font (size 1.524 1.524)) (justify left))
    )
    (property "Value" "C_10u_0603" (at 342.9 163.83 0)
      (effects (font (size 1.27 1.27) (thickness 0.15)) (justify left bottom) hide)
    )
    (property "Footprint" "antmicro-footprints:C_0603_1608Metric" (at 345.44 163.83 0)
      (effects (font (size 1.27 1.27) (thickness 0.15)) (justify left bottom) hide)
    )
    (property "Datasheet" "https://www.murata.com/products/productdetail?partno=GRM188R61A106KE69%23" (at 347.98 163.83 0)
      (effects (font (size 1.27 1.27) (thickness 0.15)) (justify left bottom) hide)
    )
    (property "Manufacturer" "Murata" (at 353.06 163.83 0)
      (effects (font (size 1.27 1.27) (thickness 0.15)) (justify left bottom) hide)
    )
    (property "MPN" "GRM188R61A106KE69D" (at 350.52 163.83 0)
      (effects (font (size 1.27 1.27) (thickness 0.15)) (justify left bottom) hide)
    )
    (property "Val" "10u" (at 338.455 185.42 90)
      (effects (font (size 1.27 1.27) (thickness 0.15)) (justify left bottom))
    )
    (property "License" "Apache-2.0" (at 355.6 163.83 0)
      (effects (font (size 1.27 1.27) (thickness 0.15)) (justify left bottom) hide)
    )
    (property "Author" "Antmicro" (at 358.14 163.83 0)
      (effects (font (size 1.27 1.27) (thickness 0.15)) (justify left bottom) hide)
    )
    (property "Voltage" "" (at 360.68 163.83 0)
      (effects (font (size 1.27 1.27)) (justify left bottom) hide)
    )
    (property "Dielectric" "template_dielectric" (at 363.22 163.83 0)
      (effects (font (size 1.27 1.27)) (justify left bottom) hide)
    )
    (property "Public" "False" (at 365.76 163.83 0)
      (effects (font (size 1.27 1.27)) (justify left bottom) hide)
    )
    (pin "1")
    (pin "2")
    (instances
      (project "antmicro-hdmi-mipi-bridge-hw"
        (path ""
          (reference "C40") (unit 1)
        )
      )
    )
  )

  (symbol (lib_id "antmicroResistors0402:R_10k_0402") (at 363.22 93.98 90) (unit 1)
    (in_bom yes) (on_board yes) (dnp no)
    (property "Reference" "R24" (at 365.125 89.535 90)
      (effects (font (size 1.524 1.524)) (justify right))
    )
    (property "Value" "R_10k_0402" (at 375.92 73.66 0)
      (effects (font (size 1.27 1.27) (thickness 0.15)) (justify left bottom) hide)
    )
    (property "Footprint" "antmicro-footprints:R_0402_1005Metric" (at 378.46 73.66 0)
      (effects (font (size 1.27 1.27) (thickness 0.15)) (justify left bottom) hide)
    )
    (property "Datasheet" "https://www.bourns.com/docs/product-datasheets/cr.pdf" (at 381 73.66 0)
      (effects (font (size 1.27 1.27) (thickness 0.15)) (justify left bottom) hide)
    )
    (property "Manufacturer" "Bourns" (at 386.08 73.66 0)
      (effects (font (size 1.27 1.27) (thickness 0.15)) (justify left bottom) hide)
    )
    (property "MPN" "CR0402-FX-1002GLF" (at 383.54 73.66 0)
      (effects (font (size 1.27 1.27) (thickness 0.15)) (justify left bottom) hide)
    )
    (property "Val" "10k" (at 368.935 90.805 90)
      (effects (font (size 1.27 1.27) (thickness 0.15)) (justify left bottom))
    )
    (property "License" "Apache-2.0" (at 388.62 73.66 0)
      (effects (font (size 1.27 1.27) (thickness 0.15)) (justify left bottom) hide)
    )
    (property "Author" "Antmicro" (at 391.16 73.66 0)
      (effects (font (size 1.27 1.27) (thickness 0.15)) (justify left bottom) hide)
    )
    (property "Tolerance" "1%" (at 373.38 73.66 0)
      (effects (font (size 1.27 1.27)) (justify left bottom) hide)
    )
    (property "Public" "False" (at 393.7 73.66 0)
      (effects (font (size 1.27 1.27)) (justify left bottom) hide)
    )
    (pin "1")
    (pin "2")
    (instances
      (project "antmicro-hdmi-mipi-bridge-hw"
        (path ""
          (reference "R24") (unit 1)
        )
      )
    )
  )

  (symbol (lib_id "antmicroCapacitors0603:C_10u_0603") (at 360.68 182.88 90) (unit 1)
    (in_bom yes) (on_board yes) (dnp no)
    (property "Reference" "C42" (at 367.03 182.88 90)
      (effects (font (size 1.524 1.524)) (justify left))
    )
    (property "Value" "C_10u_0603" (at 370.84 162.56 0)
      (effects (font (size 1.27 1.27) (thickness 0.15)) (justify left bottom) hide)
    )
    (property "Footprint" "antmicro-footprints:C_0603_1608Metric" (at 373.38 162.56 0)
      (effects (font (size 1.27 1.27) (thickness 0.15)) (justify left bottom) hide)
    )
    (property "Datasheet" "https://www.murata.com/products/productdetail?partno=GRM188R61A106KE69%23" (at 375.92 162.56 0)
      (effects (font (size 1.27 1.27) (thickness 0.15)) (justify left bottom) hide)
    )
    (property "Manufacturer" "Murata" (at 381 162.56 0)
      (effects (font (size 1.27 1.27) (thickness 0.15)) (justify left bottom) hide)
    )
    (property "MPN" "GRM188R61A106KE69D" (at 378.46 162.56 0)
      (effects (font (size 1.27 1.27) (thickness 0.15)) (justify left bottom) hide)
    )
    (property "Val" "10u" (at 366.395 184.15 90)
      (effects (font (size 1.27 1.27) (thickness 0.15)) (justify left bottom))
    )
    (property "License" "Apache-2.0" (at 383.54 162.56 0)
      (effects (font (size 1.27 1.27) (thickness 0.15)) (justify left bottom) hide)
    )
    (property "Author" "Antmicro" (at 386.08 162.56 0)
      (effects (font (size 1.27 1.27) (thickness 0.15)) (justify left bottom) hide)
    )
    (property "Voltage" "" (at 388.62 162.56 0)
      (effects (font (size 1.27 1.27)) (justify left bottom) hide)
    )
    (property "Dielectric" "template_dielectric" (at 391.16 162.56 0)
      (effects (font (size 1.27 1.27)) (justify left bottom) hide)
    )
    (property "Public" "False" (at 393.7 162.56 0)
      (effects (font (size 1.27 1.27)) (justify left bottom) hide)
    )
    (pin "1")
    (pin "2")
    (instances
      (project "antmicro-hdmi-mipi-bridge-hw"
        (path ""
          (reference "C42") (unit 1)
        )
      )
    )
  )

  (symbol (lib_id "antmicroTestPoints:TP_0.75mm_SMD") (at 106.68 201.93 0) (unit 1)
    (in_bom no) (on_board yes) (dnp no) (fields_autoplaced)
    (property "Reference" "TP6" (at 111.76 201.9299 0)
      (effects (font (size 1.27 1.27)) (justify left))
    )
    (property "Value" "TP_0.75mm_SMD" (at 121.92 209.55 0)
      (effects (font (size 1.27 1.27) (thickness 0.15)) (justify left bottom) hide)
    )
    (property "Footprint" "antmicro-footprints:TP_SMD_0.75mm" (at 121.92 212.09 0)
      (effects (font (size 1.27 1.27) (thickness 0.15)) (justify left bottom) hide)
    )
    (property "Datasheet" "" (at 121.92 214.63 0)
      (effects (font (size 1.27 1.27) (thickness 0.15)) (justify left bottom) hide)
    )
    (property "MPN" "" (at 106.68 201.93 0)
      (effects (font (size 1.27 1.27) (thickness 0.15)) (justify left bottom) hide)
    )
    (property "Manufacturer" "" (at 106.68 201.93 0)
      (effects (font (size 1.27 1.27) (thickness 0.15)) (justify left bottom) hide)
    )
    (property "Author" "Antmicro" (at 121.92 217.17 0)
      (effects (font (size 1.27 1.27) (thickness 0.15)) (justify left bottom) hide)
    )
    (property "License" "Apache-2.0" (at 121.92 219.71 0)
      (effects (font (size 1.27 1.27) (thickness 0.15)) (justify left bottom) hide)
    )
    (property "Public" "False" (at 116.84 215.9 0)
      (effects (font (size 1.27 1.27)) (justify left bottom) hide)
    )
    (pin "1")
    (instances
      (project "antmicro-hdmi-mipi-bridge-hw"
        (path ""
          (reference "TP6") (unit 1)
        )
      )
    )
  )

  (symbol (lib_id "antmicropower:+5V") (at 383.54 82.55 0) (unit 1)
    (in_bom yes) (on_board yes) (dnp no)
    (property "Reference" "#PWR0165" (at 383.54 86.36 0)
      (effects (font (size 1.27 1.27)) hide)
    )
    (property "Value" "+5V" (at 381 79.375 0)
      (effects (font (size 1.27 1.27) (thickness 0.15)) (justify left bottom))
    )
    (property "Footprint" "" (at 383.54 82.55 0)
      (effects (font (size 1.27 1.27) (thickness 0.15)) (justify left bottom) hide)
    )
    (property "Datasheet" "" (at 383.54 82.55 0)
      (effects (font (size 1.27 1.27) (thickness 0.15)) (justify left bottom) hide)
    )
    (property "Author" "Antmicro" (at 398.78 90.17 0)
      (effects (font (size 1.27 1.27) (thickness 0.15)) (justify left bottom) hide)
    )
    (property "License" "Apache-2.0" (at 398.78 92.71 0)
      (effects (font (size 1.27 1.27) (thickness 0.15)) (justify left bottom) hide)
    )
    (pin "1")
    (instances
      (project "antmicro-hdmi-mipi-bridge-hw"
        (path ""
          (reference "#PWR0165") (unit 1)
        )
      )
    )
  )

  (symbol (lib_id "antmicroCapacitors0402:C_470p_0402") (at 223.52 229.87 270) (unit 1)
    (in_bom yes) (on_board yes) (dnp no)
    (property "Reference" "C48" (at 220.98 231.14 90)
      (effects (font (size 1.524 1.524)) (justify right))
    )
    (property "Value" "C_470p_0402" (at 213.36 250.19 0)
      (effects (font (size 1.27 1.27) (thickness 0.15)) (justify left bottom) hide)
    )
    (property "Footprint" "antmicro-footprints:C_0402_1005Metric" (at 210.82 250.19 0)
      (effects (font (size 1.27 1.27) (thickness 0.15)) (justify left bottom) hide)
    )
    (property "Datasheet" "https://www.passivecomponent.com/wp-content/uploads/datasheet/WTC_MLCC_General_Purpose.pdf" (at 208.28 250.19 0)
      (effects (font (size 1.27 1.27) (thickness 0.15)) (justify left bottom) hide)
    )
    (property "Manufacturer" "Walsin" (at 203.2 250.19 0)
      (effects (font (size 1.27 1.27) (thickness 0.15)) (justify left bottom) hide)
    )
    (property "MPN" "0402B471K250CT" (at 205.74 250.19 0)
      (effects (font (size 1.27 1.27) (thickness 0.15)) (justify left bottom) hide)
    )
    (property "Val" "470p" (at 216.535 234.315 90)
      (effects (font (size 1.27 1.27) (thickness 0.15)) (justify left bottom))
    )
    (property "License" "Apache-2.0" (at 200.66 250.19 0)
      (effects (font (size 1.27 1.27) (thickness 0.15)) (justify left bottom) hide)
    )
    (property "Author" "Antmicro" (at 198.12 250.19 0)
      (effects (font (size 1.27 1.27) (thickness 0.15)) (justify left bottom) hide)
    )
    (property "Voltage" "" (at 195.58 250.19 0)
      (effects (font (size 1.27 1.27)) (justify left bottom) hide)
    )
    (property "Dielectric" "" (at 193.04 250.19 0)
      (effects (font (size 1.27 1.27)) (justify left bottom) hide)
    )
    (property "Public" "False" (at 190.5 250.19 0)
      (effects (font (size 1.27 1.27)) (justify left bottom) hide)
    )
    (pin "1")
    (pin "2")
    (instances
      (project "antmicro-hdmi-mipi-bridge-hw"
        (path ""
          (reference "C48") (unit 1)
        )
      )
    )
  )

  (symbol (lib_id "antmicropower:+3V3") (at 149.86 184.15 0) (unit 1)
    (in_bom yes) (on_board yes) (dnp no)
    (property "Reference" "#PWR0150" (at 149.86 187.96 0)
      (effects (font (size 1.27 1.27)) hide)
    )
    (property "Value" "+3V3" (at 146.685 180.975 0)
      (effects (font (size 1.27 1.27) (thickness 0.15)) (justify left bottom))
    )
    (property "Footprint" "" (at 149.86 184.15 0)
      (effects (font (size 1.27 1.27) (thickness 0.15)) (justify left bottom) hide)
    )
    (property "Datasheet" "" (at 149.86 184.15 0)
      (effects (font (size 1.27 1.27) (thickness 0.15)) (justify left bottom) hide)
    )
    (property "Author" "Antmicro" (at 165.1 186.69 0)
      (effects (font (size 1.27 1.27) (thickness 0.15)) (justify left bottom) hide)
    )
    (property "License" "Apache-2.0" (at 165.1 189.23 0)
      (effects (font (size 1.27 1.27) (thickness 0.15)) (justify left bottom) hide)
    )
    (pin "1")
    (instances
      (project "antmicro-hdmi-mipi-bridge-hw"
        (path ""
          (reference "#PWR0150") (unit 1)
        )
      )
    )
  )

  (symbol (lib_id "antmicroTVSDiodes:TPD8S009DSMR") (at 167.64 52.705 0) (unit 1)
    (in_bom yes) (on_board yes) (dnp no)
    (property "Reference" "U5" (at 175.895 46.355 0)
      (effects (font (size 1.27 1.27)))
    )
    (property "Value" "TPD8S009DSMR" (at 198.12 65.405 0)
      (effects (font (size 1.27 1.27) (thickness 0.15)) (justify left bottom) hide)
    )
    (property "Footprint" "antmicro-footprints:R-PDSO-N15" (at 198.12 60.325 0)
      (effects (font (size 1.27 1.27) (thickness 0.15)) (justify left bottom) hide)
    )
    (property "Datasheet" "https://www.ti.com/lit/ds/symlink/tpd8s009.pdf?ts=1679406571326&ref_url=https%253A%252F%252Fwww.ti.com%252Fproduct%252FTPD8S009%252Fpart-details%252FTPD8S009DSMR" (at 198.12 62.865 0)
      (effects (font (size 1.27 1.27) (thickness 0.15)) (justify left bottom) hide)
    )
    (property "MPN" "TPD8S009DSMR" (at 168.275 49.53 0)
      (effects (font (size 1.27 1.27) (thickness 0.15)) (justify left bottom))
    )
    (property "Manufacturer" "Texas Instruments" (at 198.12 67.945 0)
      (effects (font (size 1.27 1.27) (thickness 0.15)) (justify left bottom) hide)
    )
    (property "Author" "Antmicro" (at 198.12 70.485 0)
      (effects (font (size 1.27 1.27) (thickness 0.15)) (justify left bottom) hide)
    )
    (property "License" "Apache-2.0" (at 198.12 73.025 0)
      (effects (font (size 1.27 1.27) (thickness 0.15)) (justify left bottom) hide)
    )
    (pin "1")
    (pin "10")
    (pin "11")
    (pin "12")
    (pin "13")
    (pin "14")
    (pin "15")
    (pin "2")
    (pin "3")
    (pin "4")
    (pin "5")
    (pin "6")
    (pin "7")
    (pin "8")
    (pin "9")
    (pin "8")
    (instances
      (project "antmicro-hdmi-mipi-bridge-hw"
        (path ""
          (reference "U5") (unit 1)
        )
      )
    )
  )

  (symbol (lib_id "antmicropower:+3V3") (at 332.74 171.45 0) (unit 1)
    (in_bom yes) (on_board yes) (dnp no)
    (property "Reference" "#PWR0176" (at 332.74 175.26 0)
      (effects (font (size 1.27 1.27)) hide)
    )
    (property "Value" "+3V3" (at 329.565 168.275 0)
      (effects (font (size 1.27 1.27) (thickness 0.15)) (justify left bottom))
    )
    (property "Footprint" "" (at 332.74 171.45 0)
      (effects (font (size 1.27 1.27) (thickness 0.15)) (justify left bottom) hide)
    )
    (property "Datasheet" "" (at 332.74 171.45 0)
      (effects (font (size 1.27 1.27) (thickness 0.15)) (justify left bottom) hide)
    )
    (property "Author" "Antmicro" (at 347.98 173.99 0)
      (effects (font (size 1.27 1.27) (thickness 0.15)) (justify left bottom) hide)
    )
    (property "License" "Apache-2.0" (at 347.98 176.53 0)
      (effects (font (size 1.27 1.27) (thickness 0.15)) (justify left bottom) hide)
    )
    (pin "1")
    (instances
      (project "antmicro-hdmi-mipi-bridge-hw"
        (path ""
          (reference "#PWR0176") (unit 1)
        )
      )
    )
  )

  (symbol (lib_id "antmicroCapacitors0603:C_10u_0603") (at 360.68 215.9 90) (unit 1)
    (in_bom yes) (on_board yes) (dnp no)
    (property "Reference" "C43" (at 367.03 215.9 90)
      (effects (font (size 1.524 1.524)) (justify left))
    )
    (property "Value" "C_10u_0603" (at 370.84 195.58 0)
      (effects (font (size 1.27 1.27) (thickness 0.15)) (justify left bottom) hide)
    )
    (property "Footprint" "antmicro-footprints:C_0603_1608Metric" (at 373.38 195.58 0)
      (effects (font (size 1.27 1.27) (thickness 0.15)) (justify left bottom) hide)
    )
    (property "Datasheet" "https://www.murata.com/products/productdetail?partno=GRM188R61A106KE69%23" (at 375.92 195.58 0)
      (effects (font (size 1.27 1.27) (thickness 0.15)) (justify left bottom) hide)
    )
    (property "Manufacturer" "Murata" (at 381 195.58 0)
      (effects (font (size 1.27 1.27) (thickness 0.15)) (justify left bottom) hide)
    )
    (property "MPN" "GRM188R61A106KE69D" (at 378.46 195.58 0)
      (effects (font (size 1.27 1.27) (thickness 0.15)) (justify left bottom) hide)
    )
    (property "Val" "10u" (at 366.395 217.17 90)
      (effects (font (size 1.27 1.27) (thickness 0.15)) (justify left bottom))
    )
    (property "License" "Apache-2.0" (at 383.54 195.58 0)
      (effects (font (size 1.27 1.27) (thickness 0.15)) (justify left bottom) hide)
    )
    (property "Author" "Antmicro" (at 386.08 195.58 0)
      (effects (font (size 1.27 1.27) (thickness 0.15)) (justify left bottom) hide)
    )
    (property "Voltage" "" (at 388.62 195.58 0)
      (effects (font (size 1.27 1.27)) (justify left bottom) hide)
    )
    (property "Dielectric" "template_dielectric" (at 391.16 195.58 0)
      (effects (font (size 1.27 1.27)) (justify left bottom) hide)
    )
    (property "Public" "False" (at 393.7 195.58 0)
      (effects (font (size 1.27 1.27)) (justify left bottom) hide)
    )
    (pin "1")
    (pin "2")
    (instances
      (project "antmicro-hdmi-mipi-bridge-hw"
        (path ""
          (reference "C43") (unit 1)
        )
      )
    )
  )

  (symbol (lib_id "antmicropower:GND") (at 384.81 49.53 0) (unit 1)
    (in_bom yes) (on_board yes) (dnp no)
    (property "Reference" "#PWR0166" (at 384.81 55.88 0)
      (effects (font (size 1.27 1.27)) hide)
    )
    (property "Value" "GND" (at 382.905 53.975 0)
      (effects (font (size 1.27 1.27) (thickness 0.15)) (justify left bottom))
    )
    (property "Footprint" "" (at 384.81 49.53 0)
      (effects (font (size 1.27 1.27) (thickness 0.15)) (justify left bottom) hide)
    )
    (property "Datasheet" "" (at 384.81 49.53 0)
      (effects (font (size 1.27 1.27) (thickness 0.15)) (justify left bottom) hide)
    )
    (property "Author" "Antmicro" (at 393.7 57.15 0)
      (effects (font (size 1.27 1.27) (thickness 0.15)) (justify left bottom) hide)
    )
    (property "License" "Apache-2.0" (at 393.7 59.69 0)
      (effects (font (size 1.27 1.27) (thickness 0.15)) (justify left bottom) hide)
    )
    (pin "1")
    (instances
      (project "antmicro-hdmi-mipi-bridge-hw"
        (path ""
          (reference "#PWR0166") (unit 1)
        )
      )
    )
  )

  (symbol (lib_id "antmicroResistors0402:R_10k_0402") (at 321.31 93.98 270) (mirror x) (unit 1)
    (in_bom yes) (on_board yes) (dnp no)
    (property "Reference" "R22" (at 319.405 90.17 90)
      (effects (font (size 1.524 1.524)) (justify right))
    )
    (property "Value" "R_10k_0402" (at 308.61 73.66 0)
      (effects (font (size 1.27 1.27) (thickness 0.15)) (justify left bottom) hide)
    )
    (property "Footprint" "antmicro-footprints:R_0402_1005Metric" (at 306.07 73.66 0)
      (effects (font (size 1.27 1.27) (thickness 0.15)) (justify left bottom) hide)
    )
    (property "Datasheet" "https://www.bourns.com/docs/product-datasheets/cr.pdf" (at 303.53 73.66 0)
      (effects (font (size 1.27 1.27) (thickness 0.15)) (justify left bottom) hide)
    )
    (property "Manufacturer" "Bourns" (at 298.45 73.66 0)
      (effects (font (size 1.27 1.27) (thickness 0.15)) (justify left bottom) hide)
    )
    (property "MPN" "CR0402-FX-1002GLF" (at 300.99 73.66 0)
      (effects (font (size 1.27 1.27) (thickness 0.15)) (justify left bottom) hide)
    )
    (property "Val" "10k" (at 314.96 92.075 90)
      (effects (font (size 1.27 1.27) (thickness 0.15)) (justify left bottom))
    )
    (property "License" "Apache-2.0" (at 295.91 73.66 0)
      (effects (font (size 1.27 1.27) (thickness 0.15)) (justify left bottom) hide)
    )
    (property "Author" "Antmicro" (at 293.37 73.66 0)
      (effects (font (size 1.27 1.27) (thickness 0.15)) (justify left bottom) hide)
    )
    (property "Tolerance" "1%" (at 311.15 73.66 0)
      (effects (font (size 1.27 1.27)) (justify left bottom) hide)
    )
    (property "Public" "False" (at 290.83 73.66 0)
      (effects (font (size 1.27 1.27)) (justify left bottom) hide)
    )
    (pin "1")
    (pin "2")
    (instances
      (project "antmicro-hdmi-mipi-bridge-hw"
        (path ""
          (reference "R22") (unit 1)
        )
      )
    )
  )

  (symbol (lib_id "antmicroCapacitors0402:C_100n_0402") (at 92.71 257.81 90) (unit 1)
    (in_bom yes) (on_board yes) (dnp no)
    (property "Reference" "C25" (at 90.17 254.635 90)
      (effects (font (size 1.524 1.524)) (justify left))
    )
    (property "Value" "C_100n_0402" (at 102.87 237.49 0)
      (effects (font (size 1.27 1.27) (thickness 0.15)) (justify left bottom) hide)
    )
    (property "Footprint" "antmicro-footprints:C_0402_1005Metric" (at 105.41 237.49 0)
      (effects (font (size 1.27 1.27) (thickness 0.15)) (justify left bottom) hide)
    )
    (property "Datasheet" "https://www.murata.com/products/productdetail?partno=GRM155R61H104KE14%23" (at 107.95 237.49 0)
      (effects (font (size 1.27 1.27) (thickness 0.15)) (justify left bottom) hide)
    )
    (property "Manufacturer" "Murata" (at 113.03 237.49 0)
      (effects (font (size 1.27 1.27) (thickness 0.15)) (justify left bottom) hide)
    )
    (property "MPN" "GRM155R61H104KE14D" (at 110.49 237.49 0)
      (effects (font (size 1.27 1.27) (thickness 0.15)) (justify left bottom) hide)
    )
    (property "Val" "100n" (at 90.805 255.905 90)
      (effects (font (size 1.27 1.27) (thickness 0.15)) (justify left bottom))
    )
    (property "License" "Apache-2.0" (at 115.57 237.49 0)
      (effects (font (size 1.27 1.27) (thickness 0.15)) (justify left bottom) hide)
    )
    (property "Author" "Antmicro" (at 118.11 237.49 0)
      (effects (font (size 1.27 1.27) (thickness 0.15)) (justify left bottom) hide)
    )
    (property "Voltage" "50V" (at 120.65 237.49 0)
      (effects (font (size 1.27 1.27)) (justify left bottom) hide)
    )
    (property "Dielectric" "X5R" (at 123.19 237.49 0)
      (effects (font (size 1.27 1.27)) (justify left bottom) hide)
    )
    (property "Public" "False" (at 125.73 237.49 0)
      (effects (font (size 1.27 1.27)) (justify left bottom) hide)
    )
    (pin "1")
    (pin "2")
    (instances
      (project "antmicro-hdmi-mipi-bridge-hw"
        (path ""
          (reference "C25") (unit 1)
        )
      )
    )
  )

  (symbol (lib_id "antmicroCapacitors0603:C_4u7_0603") (at 234.95 267.97 90) (unit 1)
    (in_bom yes) (on_board yes) (dnp no) (fields_autoplaced)
    (property "Reference" "C54" (at 237.49 264.1536 90)
      (effects (font (size 1.524 1.524)) (justify right))
    )
    (property "Value" "C_4u7_0603" (at 245.11 247.65 0)
      (effects (font (size 1.27 1.27) (thickness 0.15)) (justify left bottom) hide)
    )
    (property "Footprint" "antmicro-footprints:C_0603_1608Metric" (at 247.65 247.65 0)
      (effects (font (size 1.27 1.27) (thickness 0.15)) (justify left bottom) hide)
    )
    (property "Datasheet" "https://product.tdk.com/en/search/capacitor/ceramic/mlcc/info?part_no=C1608X5R1V475M080AC" (at 250.19 247.65 0)
      (effects (font (size 1.27 1.27) (thickness 0.15)) (justify left bottom) hide)
    )
    (property "Manufacturer" "TDK" (at 255.27 247.65 0)
      (effects (font (size 1.27 1.27) (thickness 0.15)) (justify left bottom) hide)
    )
    (property "MPN" "C1608X5R1V475M080AC" (at 252.73 247.65 0)
      (effects (font (size 1.27 1.27) (thickness 0.15)) (justify left bottom) hide)
    )
    (property "Val" "4u7" (at 237.49 266.6936 90)
      (effects (font (size 1.27 1.27) (thickness 0.15)) (justify right))
    )
    (property "License" "Apache-2.0" (at 257.81 247.65 0)
      (effects (font (size 1.27 1.27) (thickness 0.15)) (justify left bottom) hide)
    )
    (property "Author" "Antmicro" (at 260.35 247.65 0)
      (effects (font (size 1.27 1.27) (thickness 0.15)) (justify left bottom) hide)
    )
    (property "Voltage" "" (at 262.89 247.65 0)
      (effects (font (size 1.27 1.27)) (justify left bottom) hide)
    )
    (property "Dielectric" "" (at 265.43 247.65 0)
      (effects (font (size 1.27 1.27)) (justify left bottom) hide)
    )
    (property "Public" "False" (at 267.97 247.65 0)
      (effects (font (size 1.27 1.27)) (justify left bottom) hide)
    )
    (pin "1")
    (pin "2")
    (instances
      (project "antmicro-hdmi-mipi-bridge-hw"
        (path ""
          (reference "C54") (unit 1)
        )
      )
    )
  )

  (symbol (lib_id "antmicroCapacitors0402:C_100n_0402") (at 102.87 257.81 90) (unit 1)
    (in_bom yes) (on_board yes) (dnp no)
    (property "Reference" "C26" (at 100.33 254.635 90)
      (effects (font (size 1.524 1.524)) (justify left))
    )
    (property "Value" "C_100n_0402" (at 113.03 237.49 0)
      (effects (font (size 1.27 1.27) (thickness 0.15)) (justify left bottom) hide)
    )
    (property "Footprint" "antmicro-footprints:C_0402_1005Metric" (at 115.57 237.49 0)
      (effects (font (size 1.27 1.27) (thickness 0.15)) (justify left bottom) hide)
    )
    (property "Datasheet" "https://www.murata.com/products/productdetail?partno=GRM155R61H104KE14%23" (at 118.11 237.49 0)
      (effects (font (size 1.27 1.27) (thickness 0.15)) (justify left bottom) hide)
    )
    (property "Manufacturer" "Murata" (at 123.19 237.49 0)
      (effects (font (size 1.27 1.27) (thickness 0.15)) (justify left bottom) hide)
    )
    (property "MPN" "GRM155R61H104KE14D" (at 120.65 237.49 0)
      (effects (font (size 1.27 1.27) (thickness 0.15)) (justify left bottom) hide)
    )
    (property "Val" "100n" (at 100.965 255.905 90)
      (effects (font (size 1.27 1.27) (thickness 0.15)) (justify left bottom))
    )
    (property "License" "Apache-2.0" (at 125.73 237.49 0)
      (effects (font (size 1.27 1.27) (thickness 0.15)) (justify left bottom) hide)
    )
    (property "Author" "Antmicro" (at 128.27 237.49 0)
      (effects (font (size 1.27 1.27) (thickness 0.15)) (justify left bottom) hide)
    )
    (property "Voltage" "50V" (at 130.81 237.49 0)
      (effects (font (size 1.27 1.27)) (justify left bottom) hide)
    )
    (property "Dielectric" "X5R" (at 133.35 237.49 0)
      (effects (font (size 1.27 1.27)) (justify left bottom) hide)
    )
    (property "Public" "False" (at 135.89 237.49 0)
      (effects (font (size 1.27 1.27)) (justify left bottom) hide)
    )
    (pin "1")
    (pin "2")
    (instances
      (project "antmicro-hdmi-mipi-bridge-hw"
        (path ""
          (reference "C26") (unit 1)
        )
      )
    )
  )

  (symbol (lib_id "antmicroCapacitors0402:C_100n_0402") (at 305.435 87.63 90) (mirror x) (unit 1)
    (in_bom yes) (on_board yes) (dnp no) (fields_autoplaced)
    (property "Reference" "C37" (at 308.61 88.9063 90)
      (effects (font (size 1.524 1.524)) (justify right))
    )
    (property "Value" "C_100n_0402" (at 315.595 107.95 0)
      (effects (font (size 1.27 1.27) (thickness 0.15)) (justify left bottom) hide)
    )
    (property "Footprint" "antmicro-footprints:C_0402_1005Metric" (at 318.135 107.95 0)
      (effects (font (size 1.27 1.27) (thickness 0.15)) (justify left bottom) hide)
    )
    (property "Datasheet" "https://www.murata.com/products/productdetail?partno=GRM155R61H104KE14%23" (at 320.675 107.95 0)
      (effects (font (size 1.27 1.27) (thickness 0.15)) (justify left bottom) hide)
    )
    (property "Manufacturer" "Murata" (at 325.755 107.95 0)
      (effects (font (size 1.27 1.27) (thickness 0.15)) (justify left bottom) hide)
    )
    (property "MPN" "GRM155R61H104KE14D" (at 323.215 107.95 0)
      (effects (font (size 1.27 1.27) (thickness 0.15)) (justify left bottom) hide)
    )
    (property "Val" "100n" (at 308.61 91.4463 90)
      (effects (font (size 1.27 1.27) (thickness 0.15)) (justify right))
    )
    (property "License" "Apache-2.0" (at 328.295 107.95 0)
      (effects (font (size 1.27 1.27) (thickness 0.15)) (justify left bottom) hide)
    )
    (property "Author" "Antmicro" (at 330.835 107.95 0)
      (effects (font (size 1.27 1.27) (thickness 0.15)) (justify left bottom) hide)
    )
    (property "Voltage" "50V" (at 333.375 107.95 0)
      (effects (font (size 1.27 1.27)) (justify left bottom) hide)
    )
    (property "Dielectric" "X5R" (at 335.915 107.95 0)
      (effects (font (size 1.27 1.27)) (justify left bottom) hide)
    )
    (property "Public" "False" (at 338.455 107.95 0)
      (effects (font (size 1.27 1.27)) (justify left bottom) hide)
    )
    (pin "1")
    (pin "2")
    (instances
      (project "antmicro-hdmi-mipi-bridge-hw"
        (path ""
          (reference "C37") (unit 1)
        )
      )
    )
  )

  (symbol (lib_id "antmicroCapacitors0402:C_100n_0402") (at 223.52 173.99 90) (unit 1)
    (in_bom yes) (on_board yes) (dnp no) (fields_autoplaced)
    (property "Reference" "C32" (at 226.06 170.1736 90)
      (effects (font (size 1.524 1.524)) (justify right))
    )
    (property "Value" "C_100n_0402" (at 233.68 153.67 0)
      (effects (font (size 1.27 1.27) (thickness 0.15)) (justify left bottom) hide)
    )
    (property "Footprint" "antmicro-footprints:C_0402_1005Metric" (at 236.22 153.67 0)
      (effects (font (size 1.27 1.27) (thickness 0.15)) (justify left bottom) hide)
    )
    (property "Datasheet" "https://www.murata.com/products/productdetail?partno=GRM155R61H104KE14%23" (at 238.76 153.67 0)
      (effects (font (size 1.27 1.27) (thickness 0.15)) (justify left bottom) hide)
    )
    (property "Manufacturer" "Murata" (at 243.84 153.67 0)
      (effects (font (size 1.27 1.27) (thickness 0.15)) (justify left bottom) hide)
    )
    (property "MPN" "GRM155R61H104KE14D" (at 241.3 153.67 0)
      (effects (font (size 1.27 1.27) (thickness 0.15)) (justify left bottom) hide)
    )
    (property "Val" "100n" (at 226.06 172.7136 90)
      (effects (font (size 1.27 1.27) (thickness 0.15)) (justify right))
    )
    (property "License" "Apache-2.0" (at 246.38 153.67 0)
      (effects (font (size 1.27 1.27) (thickness 0.15)) (justify left bottom) hide)
    )
    (property "Author" "Antmicro" (at 248.92 153.67 0)
      (effects (font (size 1.27 1.27) (thickness 0.15)) (justify left bottom) hide)
    )
    (property "Voltage" "50V" (at 251.46 153.67 0)
      (effects (font (size 1.27 1.27)) (justify left bottom) hide)
    )
    (property "Dielectric" "X5R" (at 254 153.67 0)
      (effects (font (size 1.27 1.27)) (justify left bottom) hide)
    )
    (property "Public" "False" (at 256.54 153.67 0)
      (effects (font (size 1.27 1.27)) (justify left bottom) hide)
    )
    (pin "1")
    (pin "2")
    (instances
      (project "antmicro-hdmi-mipi-bridge-hw"
        (path ""
          (reference "C32") (unit 1)
        )
      )
    )
  )

  (symbol (lib_id "antmicropower:GND") (at 223.52 270.51 0) (unit 1)
    (in_bom yes) (on_board yes) (dnp no)
    (property "Reference" "#PWR0187" (at 223.52 276.86 0)
      (effects (font (size 1.27 1.27)) hide)
    )
    (property "Value" "GND" (at 221.615 275.59 0)
      (effects (font (size 1.27 1.27) (thickness 0.15)) (justify left bottom))
    )
    (property "Footprint" "" (at 223.52 270.51 0)
      (effects (font (size 1.27 1.27) (thickness 0.15)) (justify left bottom) hide)
    )
    (property "Datasheet" "" (at 223.52 270.51 0)
      (effects (font (size 1.27 1.27) (thickness 0.15)) (justify left bottom) hide)
    )
    (property "Author" "Antmicro" (at 232.41 278.13 0)
      (effects (font (size 1.27 1.27) (thickness 0.15)) (justify left bottom) hide)
    )
    (property "License" "Apache-2.0" (at 232.41 280.67 0)
      (effects (font (size 1.27 1.27) (thickness 0.15)) (justify left bottom) hide)
    )
    (pin "1")
    (instances
      (project "antmicro-hdmi-mipi-bridge-hw"
        (path ""
          (reference "#PWR0187") (unit 1)
        )
      )
    )
  )

  (symbol (lib_id "antmicroVideoConnectors:HDMI-A_Molex_471511001") (at 50.8 31.75 0) (unit 1)
    (in_bom yes) (on_board yes) (dnp no)
    (property "Reference" "J4" (at 62.23 25.4 0)
      (effects (font (size 1.27 1.27) (thickness 0.15)) (justify left bottom))
    )
    (property "Value" "HDMI-A_Molex_471511001" (at 96.52 36.83 0)
      (effects (font (size 1.27 1.27) (thickness 0.15)) (justify left bottom) hide)
    )
    (property "Footprint" "antmicro-footprints:HDMI-A_Receptacle_Molex_471511001" (at 96.52 39.37 0)
      (effects (font (size 1.27 1.27) (thickness 0.15)) (justify left bottom) hide)
    )
    (property "Datasheet" "https://tools.molex.com/pdm_docs/sd/471511001_sd.pdf" (at 96.52 41.91 0)
      (effects (font (size 1.27 1.27) (thickness 0.15)) (justify left bottom) hide)
    )
    (property "Manufacturer" "Molex" (at 96.52 44.45 0)
      (effects (font (size 1.27 1.27) (thickness 0.15)) (justify left bottom) hide)
    )
    (property "MPN" "471511001" (at 58.42 27.94 0)
      (effects (font (size 1.27 1.27) (thickness 0.15)) (justify left bottom))
    )
    (property "Author" "Antmicro" (at 96.52 49.53 0)
      (effects (font (size 1.27 1.27) (thickness 0.15)) (justify left bottom) hide)
    )
    (property "License" "Apache-2.0" (at 96.52 52.07 0)
      (effects (font (size 1.27 1.27) (thickness 0.15)) (justify left bottom) hide)
    )
    (pin "1")
    (pin "10")
    (pin "11")
    (pin "12")
    (pin "13")
    (pin "14")
    (pin "15")
    (pin "16")
    (pin "17")
    (pin "18")
    (pin "19")
    (pin "2")
    (pin "3")
    (pin "4")
    (pin "5")
    (pin "6")
    (pin "7")
    (pin "8")
    (pin "9")
    (pin "SH")
    (instances
      (project "antmicro-hdmi-mipi-bridge-hw"
        (path ""
          (reference "J4") (unit 1)
        )
      )
    )
  )

  (symbol (lib_id "antmicroResistors0603:R_0R_0603") (at 232.41 196.85 0) (unit 1)
    (in_bom yes) (on_board yes) (dnp no)
    (property "Reference" "R21" (at 234.95 192.405 0)
      (effects (font (size 1.524 1.524)))
    )
    (property "Value" "R_0R_0603" (at 252.73 209.55 0)
      (effects (font (size 1.27 1.27) (thickness 0.15)) (justify left bottom) hide)
    )
    (property "Footprint" "antmicro-footprints:R_0603_1608Metric" (at 252.73 212.09 0)
      (effects (font (size 1.27 1.27) (thickness 0.15)) (justify left bottom) hide)
    )
    (property "Datasheet" "https://www.bourns.com/docs/product-datasheets/cr.pdf?sfvrsn=574d41f6_14" (at 252.73 214.63 0)
      (effects (font (size 1.27 1.27) (thickness 0.15)) (justify left bottom) hide)
    )
    (property "Manufacturer" "Bourns" (at 252.73 219.71 0)
      (effects (font (size 1.27 1.27) (thickness 0.15)) (justify left bottom) hide)
    )
    (property "MPN" "CR0603-J/-000ELF" (at 252.73 217.17 0)
      (effects (font (size 1.27 1.27) (thickness 0.15)) (justify left bottom) hide)
    )
    (property "Val" "0R" (at 233.68 194.945 0)
      (effects (font (size 1.27 1.27) (thickness 0.15)) (justify left bottom))
    )
    (property "License" "Apache-2.0" (at 252.73 222.25 0)
      (effects (font (size 1.27 1.27) (thickness 0.15)) (justify left bottom) hide)
    )
    (property "Author" "Antmicro" (at 252.73 224.79 0)
      (effects (font (size 1.27 1.27) (thickness 0.15)) (justify left bottom) hide)
    )
    (property "Tolerance" "~" (at 252.73 207.01 0)
      (effects (font (size 1.27 1.27)) (justify left bottom) hide)
    )
    (property "Current" "1A" (at 252.73 227.33 0)
      (effects (font (size 1.27 1.27) (thickness 0.15)) (justify left bottom) hide)
    )
    (property "Public" "False" (at 252.73 227.33 0)
      (effects (font (size 1.27 1.27)) (justify left bottom) hide)
    )
    (pin "1")
    (pin "2")
    (instances
      (project "antmicro-hdmi-mipi-bridge-hw"
        (path ""
          (reference "R21") (unit 1)
        )
      )
    )
  )

  (symbol (lib_id "antmicropower:PWR_FLAG") (at 192.405 246.38 180) (unit 1)
    (in_bom yes) (on_board yes) (dnp no)
    (property "Reference" "#FLG0122" (at 192.405 248.285 0)
      (effects (font (size 1.27 1.27)) hide)
    )
    (property "Value" "PWR_FLAG" (at 197.485 250.19 0)
      (effects (font (size 1.27 1.27)) (justify left))
    )
    (property "Footprint" "" (at 192.405 246.38 0)
      (effects (font (size 1.27 1.27)) hide)
    )
    (property "Datasheet" "" (at 192.405 246.38 0)
      (effects (font (size 1.27 1.27)) hide)
    )
    (pin "1")
    (instances
      (project "antmicro-hdmi-mipi-bridge-hw"
        (path ""
          (reference "#FLG0122") (unit 1)
        )
      )
    )
  )

  (symbol (lib_id "antmicroResistors0402:R_2k_0402") (at 156.21 193.04 90) (unit 1)
    (in_bom yes) (on_board yes) (dnp no)
    (property "Reference" "R17" (at 157.48 189.23 90)
      (effects (font (size 1.524 1.524)) (justify right))
    )
    (property "Value" "R_2k_0402" (at 168.91 172.72 0)
      (effects (font (size 1.27 1.27) (thickness 0.15)) (justify left bottom) hide)
    )
    (property "Footprint" "antmicro-footprints:R_0402_1005Metric" (at 171.45 172.72 0)
      (effects (font (size 1.27 1.27) (thickness 0.15)) (justify left bottom) hide)
    )
    (property "Datasheet" "https://www.bourns.com/docs/product-datasheets/cr.pdf" (at 173.99 172.72 0)
      (effects (font (size 1.27 1.27) (thickness 0.15)) (justify left bottom) hide)
    )
    (property "Manufacturer" "Bourns" (at 179.07 172.72 0)
      (effects (font (size 1.27 1.27) (thickness 0.15)) (justify left bottom) hide)
    )
    (property "MPN" "CR0402-FX-2001GLF" (at 176.53 172.72 0)
      (effects (font (size 1.27 1.27) (thickness 0.15)) (justify left bottom) hide)
    )
    (property "Val" "2k" (at 160.02 191.135 90)
      (effects (font (size 1.27 1.27) (thickness 0.15)) (justify left bottom))
    )
    (property "License" "Apache-2.0" (at 181.61 172.72 0)
      (effects (font (size 1.27 1.27) (thickness 0.15)) (justify left bottom) hide)
    )
    (property "Author" "Antmicro" (at 184.15 172.72 0)
      (effects (font (size 1.27 1.27) (thickness 0.15)) (justify left bottom) hide)
    )
    (property "Tolerance" "1%" (at 166.37 172.72 0)
      (effects (font (size 1.27 1.27)) (justify left bottom) hide)
    )
    (property "Public" "False" (at 186.69 172.72 0)
      (effects (font (size 1.27 1.27)) (justify left bottom) hide)
    )
    (pin "1")
    (pin "2")
    (instances
      (project "antmicro-hdmi-mipi-bridge-hw"
        (path ""
          (reference "R17") (unit 1)
        )
      )
    )
  )

  (symbol (lib_id "antmicroCapacitors0402:C_100n_0402") (at 318.77 46.99 90) (unit 1)
    (in_bom yes) (on_board yes) (dnp no)
    (property "Reference" "C38" (at 325.12 42.545 90)
      (effects (font (size 1.524 1.524)) (justify left))
    )
    (property "Value" "C_100n_0402" (at 328.93 26.67 0)
      (effects (font (size 1.27 1.27) (thickness 0.15)) (justify left bottom) hide)
    )
    (property "Footprint" "antmicro-footprints:C_0402_1005Metric" (at 331.47 26.67 0)
      (effects (font (size 1.27 1.27) (thickness 0.15)) (justify left bottom) hide)
    )
    (property "Datasheet" "https://www.murata.com/products/productdetail?partno=GRM155R61H104KE14%23" (at 334.01 26.67 0)
      (effects (font (size 1.27 1.27) (thickness 0.15)) (justify left bottom) hide)
    )
    (property "Manufacturer" "Murata" (at 339.09 26.67 0)
      (effects (font (size 1.27 1.27) (thickness 0.15)) (justify left bottom) hide)
    )
    (property "MPN" "GRM155R61H104KE14D" (at 336.55 26.67 0)
      (effects (font (size 1.27 1.27) (thickness 0.15)) (justify left bottom) hide)
    )
    (property "Val" "100n" (at 325.755 44.45 90)
      (effects (font (size 1.27 1.27) (thickness 0.15)) (justify left bottom))
    )
    (property "License" "Apache-2.0" (at 341.63 26.67 0)
      (effects (font (size 1.27 1.27) (thickness 0.15)) (justify left bottom) hide)
    )
    (property "Author" "Antmicro" (at 344.17 26.67 0)
      (effects (font (size 1.27 1.27) (thickness 0.15)) (justify left bottom) hide)
    )
    (property "Voltage" "50V" (at 346.71 26.67 0)
      (effects (font (size 1.27 1.27)) (justify left bottom) hide)
    )
    (property "Dielectric" "X5R" (at 349.25 26.67 0)
      (effects (font (size 1.27 1.27)) (justify left bottom) hide)
    )
    (property "Public" "False" (at 351.79 26.67 0)
      (effects (font (size 1.27 1.27)) (justify left bottom) hide)
    )
    (pin "1")
    (pin "2")
    (instances
      (project "antmicro-hdmi-mipi-bridge-hw"
        (path ""
          (reference "C38") (unit 1)
        )
      )
    )
  )

  (symbol (lib_id "antmicroFerriteBeadsandChips:FB_1kZ_0.8A_WE-CBF_0805") (at 248.285 242.57 0) (unit 1)
    (in_bom yes) (on_board yes) (dnp no)
    (property "Reference" "FB10" (at 250.825 237.49 0)
      (effects (font (size 1.524 1.524)))
    )
    (property "Value" "FB_1kZ_0.8A_WE-CBF_0805" (at 263.525 250.698 0)
      (effects (font (size 1.27 1.27) (thickness 0.15)) (justify left bottom) hide)
    )
    (property "Footprint" "antmicro-footprints:FB_0805_2012Metric" (at 263.525 253.238 0)
      (effects (font (size 1.27 1.27) (thickness 0.15)) (justify left bottom) hide)
    )
    (property "Datasheet" "https://www.we-online.com/components/products/datasheet/742792096.pdf" (at 263.525 255.778 0)
      (effects (font (size 1.27 1.27) (thickness 0.15)) (justify left bottom) hide)
    )
    (property "MPN" "742792096" (at 263.525 245.11 0)
      (effects (font (size 1.27 1.27) (thickness 0.15)) (justify left bottom) hide)
    )
    (property "Manufacturer" "Würth Elektronik" (at 263.525 258.318 0)
      (effects (font (size 1.27 1.27) (thickness 0.15)) (justify left bottom) hide)
    )
    (property "Author" "Antmicro" (at 263.525 260.858 0)
      (effects (font (size 1.27 1.27) (thickness 0.15)) (justify left bottom) hide)
    )
    (property "License" "Apache-2.0" (at 263.525 263.398 0)
      (effects (font (size 1.27 1.27) (thickness 0.15)) (justify left bottom) hide)
    )
    (property "Val" "1kZ/0.8A" (at 246.38 240.665 0)
      (effects (font (size 1.27 1.27)) (justify left bottom))
    )
    (property "Current" "" (at 268.605 265.43 0)
      (effects (font (size 1.27 1.27) (thickness 0.15)) (justify left bottom) hide)
    )
    (property "Public" "False" (at 268.605 257.81 0)
      (effects (font (size 1.27 1.27)) (justify left bottom) hide)
    )
    (pin "1")
    (pin "2")
    (instances
      (project "antmicro-hdmi-mipi-bridge-hw"
        (path ""
          (reference "FB10") (unit 1)
        )
      )
    )
  )

  (symbol (lib_id "antmicropower:PWR_FLAG") (at 215.265 211.455 0) (unit 1)
    (in_bom yes) (on_board yes) (dnp no)
    (property "Reference" "#FLG0116" (at 215.265 209.55 0)
      (effects (font (size 1.27 1.27)) hide)
    )
    (property "Value" "PWR_FLAG" (at 210.185 207.645 0)
      (effects (font (size 1.27 1.27)) (justify left))
    )
    (property "Footprint" "" (at 215.265 211.455 0)
      (effects (font (size 1.27 1.27)) hide)
    )
    (property "Datasheet" "" (at 215.265 211.455 0)
      (effects (font (size 1.27 1.27)) hide)
    )
    (pin "1")
    (instances
      (project "antmicro-hdmi-mipi-bridge-hw"
        (path ""
          (reference "#FLG0116") (unit 1)
        )
      )
    )
  )

  (symbol (lib_id "antmicroCapacitors0402:C_100n_0402") (at 223.52 204.47 90) (unit 1)
    (in_bom yes) (on_board yes) (dnp no) (fields_autoplaced)
    (property "Reference" "C34" (at 226.06 200.6536 90)
      (effects (font (size 1.524 1.524)) (justify right))
    )
    (property "Value" "C_100n_0402" (at 233.68 184.15 0)
      (effects (font (size 1.27 1.27) (thickness 0.15)) (justify left bottom) hide)
    )
    (property "Footprint" "antmicro-footprints:C_0402_1005Metric" (at 236.22 184.15 0)
      (effects (font (size 1.27 1.27) (thickness 0.15)) (justify left bottom) hide)
    )
    (property "Datasheet" "https://www.murata.com/products/productdetail?partno=GRM155R61H104KE14%23" (at 238.76 184.15 0)
      (effects (font (size 1.27 1.27) (thickness 0.15)) (justify left bottom) hide)
    )
    (property "Manufacturer" "Murata" (at 243.84 184.15 0)
      (effects (font (size 1.27 1.27) (thickness 0.15)) (justify left bottom) hide)
    )
    (property "MPN" "GRM155R61H104KE14D" (at 241.3 184.15 0)
      (effects (font (size 1.27 1.27) (thickness 0.15)) (justify left bottom) hide)
    )
    (property "Val" "100n" (at 226.06 203.1936 90)
      (effects (font (size 1.27 1.27) (thickness 0.15)) (justify right))
    )
    (property "License" "Apache-2.0" (at 246.38 184.15 0)
      (effects (font (size 1.27 1.27) (thickness 0.15)) (justify left bottom) hide)
    )
    (property "Author" "Antmicro" (at 248.92 184.15 0)
      (effects (font (size 1.27 1.27) (thickness 0.15)) (justify left bottom) hide)
    )
    (property "Voltage" "50V" (at 251.46 184.15 0)
      (effects (font (size 1.27 1.27)) (justify left bottom) hide)
    )
    (property "Dielectric" "X5R" (at 254 184.15 0)
      (effects (font (size 1.27 1.27)) (justify left bottom) hide)
    )
    (property "Public" "False" (at 256.54 184.15 0)
      (effects (font (size 1.27 1.27)) (justify left bottom) hide)
    )
    (pin "1")
    (pin "2")
    (instances
      (project "antmicro-hdmi-mipi-bridge-hw"
        (path ""
          (reference "C34") (unit 1)
        )
      )
    )
  )

  (symbol (lib_id "antmicroInterfaceControllers:TC358743XBG") (at 158.75 196.85 0) (unit 2)
    (in_bom yes) (on_board yes) (dnp no)
    (property "Reference" "U4" (at 170.815 190.5 0)
      (effects (font (size 1.27 1.27)))
    )
    (property "Value" "TC358743XBG" (at 199.39 189.23 0)
      (effects (font (size 1.27 1.27) (thickness 0.15)) (justify left bottom) hide)
    )
    (property "Footprint" "antmicro-footprints:BGA-64_8x8_6.0x6.0mm" (at 199.39 191.77 0)
      (effects (font (size 1.27 1.27) (thickness 0.15)) (justify left bottom) hide)
    )
    (property "Datasheet" "https://toshiba.semicon-storage.com/info/TC358743XBG_datasheet_en_20171026.pdf?did=35655&prodName=TC358743XBG" (at 199.39 194.31 0)
      (effects (font (size 1.27 1.27) (thickness 0.15)) (justify left bottom) hide)
    )
    (property "MPN" "TC358743XBG" (at 164.465 193.675 0)
      (effects (font (size 1.27 1.27) (thickness 0.15)) (justify left bottom))
    )
    (property "Manufacturer" "Toshiba" (at 199.39 199.39 0)
      (effects (font (size 1.27 1.27) (thickness 0.15)) (justify left bottom) hide)
    )
    (property "Author" "Antmicro" (at 199.39 201.93 0)
      (effects (font (size 1.27 1.27) (thickness 0.15)) (justify left bottom) hide)
    )
    (property "License" "Apache-2.0" (at 199.39 204.47 0)
      (effects (font (size 1.27 1.27) (thickness 0.15)) (justify left bottom) hide)
    )
    (pin "A7")
    (pin "A8")
    (pin "B4")
    (pin "B7")
    (pin "B8")
    (pin "C1")
    (pin "C2")
    (pin "C7")
    (pin "C8")
    (pin "D1")
    (pin "D2")
    (pin "D7")
    (pin "D8")
    (pin "E1")
    (pin "E2")
    (pin "E7")
    (pin "E8")
    (pin "F1")
    (pin "F2")
    (pin "G1")
    (pin "G3")
    (pin "G4")
    (pin "G6")
    (pin "H1")
    (pin "H2")
    (pin "H3")
    (pin "H4")
    (pin "H6")
    (pin "A1")
    (pin "A2")
    (pin "A3")
    (pin "B1")
    (pin "B2")
    (pin "B3")
    (pin "B5")
    (pin "C3")
    (pin "C4")
    (pin "C5")
    (pin "C6")
    (pin "D3")
    (pin "D4")
    (pin "D5")
    (pin "D6")
    (pin "E3")
    (pin "E4")
    (pin "E5")
    (pin "E6")
    (pin "F3")
    (pin "F4")
    (pin "F5")
    (pin "F6")
    (pin "G2")
    (pin "G5")
    (pin "H5")
    (pin "H7")
    (pin "H8")
    (pin "A4")
    (pin "A5")
    (pin "A6")
    (pin "B6")
    (pin "F7")
    (pin "F8")
    (pin "G7")
    (pin "G8")
    (instances
      (project "antmicro-hdmi-mipi-bridge-hw"
        (path ""
          (reference "U4") (unit 2)
        )
      )
    )
  )

  (symbol (lib_id "antmicropower:GND") (at 78.74 93.345 0) (unit 1)
    (in_bom yes) (on_board yes) (dnp no)
    (property "Reference" "#PWR0149" (at 78.74 99.695 0)
      (effects (font (size 1.27 1.27)) hide)
    )
    (property "Value" "GND" (at 76.835 97.79 0)
      (effects (font (size 1.27 1.27) (thickness 0.15)) (justify left bottom))
    )
    (property "Footprint" "" (at 78.74 93.345 0)
      (effects (font (size 1.27 1.27) (thickness 0.15)) (justify left bottom) hide)
    )
    (property "Datasheet" "" (at 78.74 93.345 0)
      (effects (font (size 1.27 1.27) (thickness 0.15)) (justify left bottom) hide)
    )
    (property "Author" "Antmicro" (at 87.63 100.965 0)
      (effects (font (size 1.27 1.27) (thickness 0.15)) (justify left bottom) hide)
    )
    (property "License" "Apache-2.0" (at 87.63 103.505 0)
      (effects (font (size 1.27 1.27) (thickness 0.15)) (justify left bottom) hide)
    )
    (pin "1")
    (instances
      (project "antmicro-hdmi-mipi-bridge-hw"
        (path ""
          (reference "#PWR0149") (unit 1)
        )
      )
    )
  )

  (symbol (lib_id "antmicroResistors0603:R_0R_0603") (at 193.675 240.03 0) (unit 1)
    (in_bom yes) (on_board yes) (dnp no)
    (property "Reference" "R18" (at 196.215 242.57 0)
      (effects (font (size 1.524 1.524)))
    )
    (property "Value" "R_0R_0603" (at 213.995 252.73 0)
      (effects (font (size 1.27 1.27) (thickness 0.15)) (justify left bottom) hide)
    )
    (property "Footprint" "antmicro-footprints:R_0603_1608Metric" (at 213.995 255.27 0)
      (effects (font (size 1.27 1.27) (thickness 0.15)) (justify left bottom) hide)
    )
    (property "Datasheet" "https://www.bourns.com/docs/product-datasheets/cr.pdf?sfvrsn=574d41f6_14" (at 213.995 257.81 0)
      (effects (font (size 1.27 1.27) (thickness 0.15)) (justify left bottom) hide)
    )
    (property "Manufacturer" "Bourns" (at 213.995 262.89 0)
      (effects (font (size 1.27 1.27) (thickness 0.15)) (justify left bottom) hide)
    )
    (property "MPN" "CR0603-J/-000ELF" (at 213.995 260.35 0)
      (effects (font (size 1.27 1.27) (thickness 0.15)) (justify left bottom) hide)
    )
    (property "Val" "0R" (at 194.945 245.11 0)
      (effects (font (size 1.27 1.27) (thickness 0.15)) (justify left bottom))
    )
    (property "License" "Apache-2.0" (at 213.995 265.43 0)
      (effects (font (size 1.27 1.27) (thickness 0.15)) (justify left bottom) hide)
    )
    (property "Author" "Antmicro" (at 213.995 267.97 0)
      (effects (font (size 1.27 1.27) (thickness 0.15)) (justify left bottom) hide)
    )
    (property "Tolerance" "~" (at 213.995 250.19 0)
      (effects (font (size 1.27 1.27)) (justify left bottom) hide)
    )
    (property "Current" "1A" (at 213.995 270.51 0)
      (effects (font (size 1.27 1.27) (thickness 0.15)) (justify left bottom) hide)
    )
    (property "Public" "False" (at 213.995 270.51 0)
      (effects (font (size 1.27 1.27)) (justify left bottom) hide)
    )
    (pin "1")
    (pin "2")
    (instances
      (project "antmicro-hdmi-mipi-bridge-hw"
        (path ""
          (reference "R18") (unit 1)
        )
      )
    )
  )

  (symbol (lib_id "antmicroInterfaceControllers:TC358743XBG") (at 105.41 228.6 0) (unit 3)
    (in_bom yes) (on_board yes) (dnp no)
    (property "Reference" "U4" (at 113.665 222.25 0)
      (effects (font (size 1.27 1.27)) (justify left))
    )
    (property "Value" "TC358743XBG" (at 146.05 220.98 0)
      (effects (font (size 1.27 1.27) (thickness 0.15)) (justify left bottom) hide)
    )
    (property "Footprint" "antmicro-footprints:BGA-64_8x8_6.0x6.0mm" (at 146.05 223.52 0)
      (effects (font (size 1.27 1.27) (thickness 0.15)) (justify left bottom) hide)
    )
    (property "Datasheet" "https://toshiba.semicon-storage.com/info/TC358743XBG_datasheet_en_20171026.pdf?did=35655&prodName=TC358743XBG" (at 146.05 226.06 0)
      (effects (font (size 1.27 1.27) (thickness 0.15)) (justify left bottom) hide)
    )
    (property "MPN" "TC358743XBG" (at 108.585 225.425 0)
      (effects (font (size 1.27 1.27) (thickness 0.15)) (justify left bottom))
    )
    (property "Manufacturer" "Toshiba" (at 146.05 231.14 0)
      (effects (font (size 1.27 1.27) (thickness 0.15)) (justify left bottom) hide)
    )
    (property "Author" "Antmicro" (at 146.05 233.68 0)
      (effects (font (size 1.27 1.27) (thickness 0.15)) (justify left bottom) hide)
    )
    (property "License" "Apache-2.0" (at 146.05 236.22 0)
      (effects (font (size 1.27 1.27) (thickness 0.15)) (justify left bottom) hide)
    )
    (pin "A7")
    (pin "A8")
    (pin "B4")
    (pin "B7")
    (pin "B8")
    (pin "C1")
    (pin "C2")
    (pin "C7")
    (pin "C8")
    (pin "D1")
    (pin "D2")
    (pin "D7")
    (pin "D8")
    (pin "E1")
    (pin "E2")
    (pin "E7")
    (pin "E8")
    (pin "F1")
    (pin "F2")
    (pin "G1")
    (pin "G3")
    (pin "G4")
    (pin "G6")
    (pin "H1")
    (pin "H2")
    (pin "H3")
    (pin "H4")
    (pin "H6")
    (pin "A1")
    (pin "A2")
    (pin "A3")
    (pin "B1")
    (pin "B2")
    (pin "B3")
    (pin "B5")
    (pin "C3")
    (pin "C4")
    (pin "C5")
    (pin "C6")
    (pin "D3")
    (pin "D4")
    (pin "D5")
    (pin "D6")
    (pin "E3")
    (pin "E4")
    (pin "E5")
    (pin "E6")
    (pin "F3")
    (pin "F4")
    (pin "F5")
    (pin "F6")
    (pin "G2")
    (pin "G5")
    (pin "H5")
    (pin "H7")
    (pin "H8")
    (pin "A4")
    (pin "A5")
    (pin "A6")
    (pin "B6")
    (pin "F7")
    (pin "F8")
    (pin "G7")
    (pin "G8")
    (instances
      (project "antmicro-hdmi-mipi-bridge-hw"
        (path ""
          (reference "U4") (unit 3)
        )
      )
    )
  )

  (symbol (lib_id "antmicropower:GND") (at 186.69 252.73 0) (unit 1)
    (in_bom yes) (on_board yes) (dnp no)
    (property "Reference" "#PWR0158" (at 186.69 259.08 0)
      (effects (font (size 1.27 1.27)) hide)
    )
    (property "Value" "GND" (at 184.785 257.175 0)
      (effects (font (size 1.27 1.27) (thickness 0.15)) (justify left bottom))
    )
    (property "Footprint" "" (at 186.69 252.73 0)
      (effects (font (size 1.27 1.27) (thickness 0.15)) (justify left bottom) hide)
    )
    (property "Datasheet" "" (at 186.69 252.73 0)
      (effects (font (size 1.27 1.27) (thickness 0.15)) (justify left bottom) hide)
    )
    (property "Author" "Antmicro" (at 195.58 260.35 0)
      (effects (font (size 1.27 1.27) (thickness 0.15)) (justify left bottom) hide)
    )
    (property "License" "Apache-2.0" (at 195.58 262.89 0)
      (effects (font (size 1.27 1.27) (thickness 0.15)) (justify left bottom) hide)
    )
    (pin "1")
    (instances
      (project "antmicro-hdmi-mipi-bridge-hw"
        (path ""
          (reference "#PWR0158") (unit 1)
        )
      )
    )
  )

  (symbol (lib_id "antmicropower:GND") (at 156.21 245.11 0) (unit 1)
    (in_bom yes) (on_board yes) (dnp no)
    (property "Reference" "#PWR0148" (at 156.21 251.46 0)
      (effects (font (size 1.27 1.27)) hide)
    )
    (property "Value" "GND" (at 154.305 249.555 0)
      (effects (font (size 1.27 1.27) (thickness 0.15)) (justify left bottom))
    )
    (property "Footprint" "" (at 156.21 245.11 0)
      (effects (font (size 1.27 1.27) (thickness 0.15)) (justify left bottom) hide)
    )
    (property "Datasheet" "" (at 156.21 245.11 0)
      (effects (font (size 1.27 1.27) (thickness 0.15)) (justify left bottom) hide)
    )
    (property "Author" "Antmicro" (at 165.1 252.73 0)
      (effects (font (size 1.27 1.27) (thickness 0.15)) (justify left bottom) hide)
    )
    (property "License" "Apache-2.0" (at 165.1 255.27 0)
      (effects (font (size 1.27 1.27) (thickness 0.15)) (justify left bottom) hide)
    )
    (pin "1")
    (instances
      (project "antmicro-hdmi-mipi-bridge-hw"
        (path ""
          (reference "#PWR0148") (unit 1)
        )
      )
    )
  )

  (symbol (lib_id "antmicropower:PWR_FLAG") (at 215.265 180.975 0) (unit 1)
    (in_bom yes) (on_board yes) (dnp no)
    (property "Reference" "#FLG0120" (at 215.265 179.07 0)
      (effects (font (size 1.27 1.27)) hide)
    )
    (property "Value" "PWR_FLAG" (at 210.185 177.165 0)
      (effects (font (size 1.27 1.27)) (justify left))
    )
    (property "Footprint" "" (at 215.265 180.975 0)
      (effects (font (size 1.27 1.27)) hide)
    )
    (property "Datasheet" "" (at 215.265 180.975 0)
      (effects (font (size 1.27 1.27)) hide)
    )
    (pin "1")
    (instances
      (project "antmicro-hdmi-mipi-bridge-hw"
        (path ""
          (reference "#FLG0120") (unit 1)
        )
      )
    )
  )

  (symbol (lib_id "antmicropower:GND") (at 234.95 270.51 0) (unit 1)
    (in_bom yes) (on_board yes) (dnp no)
    (property "Reference" "#PWR0188" (at 234.95 276.86 0)
      (effects (font (size 1.27 1.27)) hide)
    )
    (property "Value" "GND" (at 233.045 275.59 0)
      (effects (font (size 1.27 1.27) (thickness 0.15)) (justify left bottom))
    )
    (property "Footprint" "" (at 234.95 270.51 0)
      (effects (font (size 1.27 1.27) (thickness 0.15)) (justify left bottom) hide)
    )
    (property "Datasheet" "" (at 234.95 270.51 0)
      (effects (font (size 1.27 1.27) (thickness 0.15)) (justify left bottom) hide)
    )
    (property "Author" "Antmicro" (at 243.84 278.13 0)
      (effects (font (size 1.27 1.27) (thickness 0.15)) (justify left bottom) hide)
    )
    (property "License" "Apache-2.0" (at 243.84 280.67 0)
      (effects (font (size 1.27 1.27) (thickness 0.15)) (justify left bottom) hide)
    )
    (pin "1")
    (instances
      (project "antmicro-hdmi-mipi-bridge-hw"
        (path ""
          (reference "#PWR0188") (unit 1)
        )
      )
    )
  )

  (symbol (lib_id "antmicroCapacitors0402:C_47p_0402") (at 384.81 46.99 90) (unit 1)
    (in_bom yes) (on_board yes) (dnp no)
    (property "Reference" "C46" (at 391.795 43.18 90)
      (effects (font (size 1.524 1.524)) (justify left))
    )
    (property "Value" "C_47p_0402" (at 394.97 26.67 0)
      (effects (font (size 1.27 1.27) (thickness 0.15)) (justify left bottom) hide)
    )
    (property "Footprint" "antmicro-footprints:C_0402_1005Metric" (at 397.51 26.67 0)
      (effects (font (size 1.27 1.27) (thickness 0.15)) (justify left bottom) hide)
    )
    (property "Datasheet" "https://www.kemet.com/en/us/capacitors/product/C0402C470J5GACTU.html" (at 400.05 26.67 0)
      (effects (font (size 1.27 1.27) (thickness 0.15)) (justify left bottom) hide)
    )
    (property "Manufacturer" "KEMET" (at 405.13 26.67 0)
      (effects (font (size 1.27 1.27) (thickness 0.15)) (justify left bottom) hide)
    )
    (property "MPN" "C0402C470J5GACTU" (at 402.59 26.67 0)
      (effects (font (size 1.27 1.27) (thickness 0.15)) (justify left bottom) hide)
    )
    (property "Val" "47p" (at 391.16 44.45 90)
      (effects (font (size 1.27 1.27) (thickness 0.15)) (justify left bottom))
    )
    (property "License" "Apache-2.0" (at 407.67 26.67 0)
      (effects (font (size 1.27 1.27) (thickness 0.15)) (justify left bottom) hide)
    )
    (property "Author" "Antmicro" (at 410.21 26.67 0)
      (effects (font (size 1.27 1.27) (thickness 0.15)) (justify left bottom) hide)
    )
    (property "Voltage" "" (at 412.75 26.67 0)
      (effects (font (size 1.27 1.27)) (justify left bottom) hide)
    )
    (property "Dielectric" "C0G" (at 415.29 26.67 0)
      (effects (font (size 1.27 1.27)) (justify left bottom) hide)
    )
    (property "Public" "False" (at 417.83 26.67 0)
      (effects (font (size 1.27 1.27)) (justify left bottom) hide)
    )
    (pin "1")
    (pin "2")
    (instances
      (project "antmicro-hdmi-mipi-bridge-hw"
        (path ""
          (reference "C46") (unit 1)
        )
      )
    )
  )

  (symbol (lib_id "antmicropower:GND") (at 223.52 222.25 0) (unit 1)
    (in_bom yes) (on_board yes) (dnp no)
    (property "Reference" "#PWR0160" (at 223.52 228.6 0)
      (effects (font (size 1.27 1.27)) hide)
    )
    (property "Value" "GND" (at 225.425 224.79 0)
      (effects (font (size 1.27 1.27) (thickness 0.15)) (justify left bottom))
    )
    (property "Footprint" "" (at 223.52 222.25 0)
      (effects (font (size 1.27 1.27) (thickness 0.15)) (justify left bottom) hide)
    )
    (property "Datasheet" "" (at 223.52 222.25 0)
      (effects (font (size 1.27 1.27) (thickness 0.15)) (justify left bottom) hide)
    )
    (property "Author" "Antmicro" (at 232.41 229.87 0)
      (effects (font (size 1.27 1.27) (thickness 0.15)) (justify left bottom) hide)
    )
    (property "License" "Apache-2.0" (at 232.41 232.41 0)
      (effects (font (size 1.27 1.27) (thickness 0.15)) (justify left bottom) hide)
    )
    (pin "1")
    (instances
      (project "antmicro-hdmi-mipi-bridge-hw"
        (path ""
          (reference "#PWR0160") (unit 1)
        )
      )
    )
  )

  (symbol (lib_id "antmicropower:GND") (at 328.93 49.53 0) (unit 1)
    (in_bom yes) (on_board yes) (dnp no)
    (property "Reference" "#PWR0171" (at 328.93 55.88 0)
      (effects (font (size 1.27 1.27)) hide)
    )
    (property "Value" "GND" (at 327.025 53.975 0)
      (effects (font (size 1.27 1.27) (thickness 0.15)) (justify left bottom))
    )
    (property "Footprint" "" (at 328.93 49.53 0)
      (effects (font (size 1.27 1.27) (thickness 0.15)) (justify left bottom) hide)
    )
    (property "Datasheet" "" (at 328.93 49.53 0)
      (effects (font (size 1.27 1.27) (thickness 0.15)) (justify left bottom) hide)
    )
    (property "Author" "Antmicro" (at 337.82 57.15 0)
      (effects (font (size 1.27 1.27) (thickness 0.15)) (justify left bottom) hide)
    )
    (property "License" "Apache-2.0" (at 337.82 59.69 0)
      (effects (font (size 1.27 1.27) (thickness 0.15)) (justify left bottom) hide)
    )
    (pin "1")
    (instances
      (project "antmicro-hdmi-mipi-bridge-hw"
        (path ""
          (reference "#PWR0171") (unit 1)
        )
      )
    )
  )
)
